G04 ================== begin FILE IDENTIFICATION RECORD ==================*
G04 Layout Name:  x887571-005_osp.brd*
G04 Film Name:    lyr2*
G04 File Format:  Gerber RS274X*
G04 File Origin:  Cadence Allegro 16.3-S036*
G04 Origin Date:  Thu Jul 03 00:06:56 2014*
G04 *
G04 Layer:  VIA CLASS/LYR2*
G04 Layer:  PIN/LYR2*
G04 Layer:  ETCH/LYR2*
G04 Layer:  DRAWING FORMAT/COMMON TEXT*
G04 Layer:  BOARD GEOMETRY/LAYER 2 TEXT*
G04 *
G04 Offset:    (0.0000 0.0000)*
G04 Mirror:    No*
G04 Mode:      Positive*
G04 Rotation:  0*
G04 FullContactRelief:  No*
G04 UndefLineWidth:     4.0000*
G04 ================== end FILE IDENTIFICATION RECORD ====================*
%FSLAX25Y25*MOIN*%
%IR0*IPPOS*OFA0.00000B0.00000*MIA0B0*SFA1.00000B1.00000*%
%ADD12C,.022*%
%ADD15C,.05*%
%ADD14C,.032*%
%ADD17C,.061*%
%ADD20C,.044*%
%ADD11C,.026*%
%ADD21C,.027*%
%ADD13C,.054*%
%ADD18C,.058*%
%ADD19C,.079*%
%ADD16C,.22*%
%ADD10C,.178*%
%ADD22C,.01*%
%ADD23C,.012*%
%ADD24C,.013*%
%ADD25C,.015*%
%ADD26C,.004*%
%ADD27C,.005*%
%ADD28C,.006*%
%ADD29C,.007*%
%ADD30C,.008*%
%ADD40C,.032*%
%ADD41C,.051*%
%ADD42C,.046*%
%ADD38C,.064*%
%ADD37C,.073*%
%ADD33C,.080001*%
%ADD39C,.074*%
%ADD31C,.091001*%
%ADD44C,.098*%
%ADD43C,.099*%
%ADD36C,.092914*%
%ADD35C,.092914*%
%ADD34C,.154001*%
%ADD32C,.186001*%
G75*
%LPD*%
G75*
G36*
G01X-1440241Y-14409D02*
Y9213D01*
G02X-1432598Y16855I7643J0D01*
G01X5433D01*
G02X15044Y7244I0J-9611D01*
G01Y-135827D01*
G03X19213Y-139995I4169J0D01*
G01X19611D01*
Y-175039D01*
G02X10000Y-184650I-9611J0D01*
G01X-335335D01*
G03X-339503Y-188819I0J-4169D01*
G01Y-194650D01*
X-406560D01*
Y-188819D01*
G03X-410728Y-184650I-4169J0D01*
G01X-888784D01*
Y-183850D01*
X-904784D01*
Y-184634D01*
X-905000Y-184850D01*
X-1206847D01*
X-1206935Y-184938D01*
X-1206981Y-184957D01*
G03X-1209582Y-188819I1568J-3862D01*
G01Y-194650D01*
X-1276639D01*
Y-188819D01*
G03X-1280807Y-184650I-4169J0D01*
G01X-1657323D01*
G02X-1661028Y-180945I0J3706D01*
G01Y16175D01*
X-1660094Y17110D01*
X-1625221D01*
X-1624287Y16175D01*
Y-18937D01*
G03X-1617131I3578J0D01*
G01Y16175D01*
X-1616216Y17090D01*
X-1461304D01*
X-1460389Y16175D01*
Y-14409D01*
G03X-1452283Y-22515I8106J0D01*
G01X-1448346D01*
G03X-1440241Y-14409I0J8106D01*
G37*
G36*
G01X-901784Y-186850D02*
X-889784D01*
Y-184850D01*
X-901784D01*
X-903784D01*
Y-186850D01*
X-901784D01*
G37*
%LPC*%
G75*
G36*
G01X-91156Y-44741D02*
G02X-83889Y-30498I1195J8365D01*
G02X-84008Y-42373I-6071J-5877D01*
G02X-88932Y-44763I-5953J5997D01*
G03X-89046Y-45725I65J-496D01*
G01X-87619Y-46273D01*
X-86454Y-48771D01*
X-86773Y-49787D01*
X-90342Y-51451D01*
X-91325Y-51043D01*
X-92490Y-48545D01*
X-91600Y-45958D01*
X-91020Y-45688D01*
G03X-91156Y-44741I-211J453D01*
G37*
G36*
G01X-134463D02*
G02X-127197Y-30498I1195J8365D01*
G02X-127315Y-42373I-6071J-5877D01*
G02X-132239Y-44763I-5953J5997D01*
G03X-132353Y-45725I65J-496D01*
G01X-130926Y-46273D01*
X-129761Y-48771D01*
X-130080Y-49787D01*
X-133649Y-51451D01*
X-134632Y-51043D01*
X-135797Y-48545D01*
X-134907Y-45958D01*
X-134327Y-45688D01*
G03X-134463Y-44741I-211J453D01*
G37*
G36*
G01X-961235D02*
G02X-953921Y-30548I1195J8365D01*
G02X-954078Y-42365I-6119J-5828D01*
G02X-959010Y-44763I-5961J5989D01*
G03X-959125Y-45725I65J-496D01*
G01X-957697Y-46273D01*
X-956533Y-48771D01*
X-956852Y-49787D01*
X-960420Y-51451D01*
X-961404Y-51043D01*
X-962569Y-48545D01*
X-961679Y-45958D01*
X-961099Y-45688D01*
G03X-961235Y-44741I-211J453D01*
G37*
G36*
G01X-1004542D02*
G02X-997228Y-30548I1195J8365D01*
G02X-997385Y-42365I-6119J-5828D01*
G02X-1002317Y-44763I-5961J5989D01*
G03X-1002432Y-45725I65J-496D01*
G01X-1001004Y-46273D01*
X-999840Y-48771D01*
X-1000159Y-49787D01*
X-1003727Y-51451D01*
X-1004711Y-51043D01*
X-1005876Y-48545D01*
X-1004986Y-45958D01*
X-1004406Y-45688D01*
G03X-1004542Y-44741I-211J453D01*
G37*
G36*
G01X-21024Y-117826D02*
Y-129370D01*
G02X-44409I-11693J0D01*
G01Y-117826D01*
G02X-21024I11693J12078D01*
G37*
G36*
G01X-86773Y-64748D02*
X-90342Y-66412D01*
X-91325Y-66003D01*
X-92490Y-63505D01*
X-91600Y-60919D01*
X-90172Y-60253D01*
X-87619Y-61234D01*
X-86454Y-63732D01*
X-86773Y-64748D01*
G37*
G36*
G01X-90207Y-52047D02*
X-86678Y-50303D01*
X-85685Y-50689D01*
X-84464Y-53160D01*
X-85296Y-55766D01*
X-86708Y-56464D01*
X-89283Y-55541D01*
X-90504Y-53070D01*
X-90207Y-52047D01*
G37*
G36*
G01X-86773Y-79708D02*
X-90342Y-81372D01*
X-91325Y-80964D01*
X-92490Y-78466D01*
X-91600Y-75879D01*
X-90172Y-75214D01*
X-87619Y-76194D01*
X-86454Y-78692D01*
X-86773Y-79708D01*
G37*
G36*
G01X-90207Y-81968D02*
X-86678Y-80224D01*
X-85685Y-80610D01*
X-84464Y-83081D01*
X-85296Y-85687D01*
X-86708Y-86385D01*
X-89283Y-85462D01*
X-90504Y-82991D01*
X-90207Y-81968D01*
G37*
G36*
G01Y-67007D02*
X-86678Y-65263D01*
X-85685Y-65650D01*
X-84464Y-68121D01*
X-85296Y-70727D01*
X-86708Y-71424D01*
X-89283Y-70501D01*
X-90504Y-68030D01*
X-90207Y-67007D01*
G37*
G36*
G01X-86773Y-94669D02*
X-90342Y-96333D01*
X-91325Y-95924D01*
X-92490Y-93427D01*
X-91600Y-90840D01*
X-90172Y-90174D01*
X-87619Y-91155D01*
X-86454Y-93653D01*
X-86773Y-94669D01*
G37*
G36*
G01X-90207Y-96928D02*
X-86678Y-95185D01*
X-85685Y-95571D01*
X-84464Y-98042D01*
X-85296Y-100648D01*
X-86708Y-101346D01*
X-89283Y-100423D01*
X-90504Y-97952D01*
X-90207Y-96928D01*
G37*
G36*
G01X-95632Y-49787D02*
X-99200Y-51451D01*
X-100184Y-51043D01*
X-101348Y-48545D01*
X-100458Y-45958D01*
X-99031Y-45293D01*
X-96477Y-46273D01*
X-95312Y-48771D01*
X-95632Y-49787D01*
G37*
G36*
G01X-99066Y-52047D02*
X-95536Y-50303D01*
X-94543Y-50689D01*
X-93323Y-53160D01*
X-94154Y-55766D01*
X-95566Y-56464D01*
X-98142Y-55541D01*
X-99362Y-53070D01*
X-99066Y-52047D01*
G37*
G36*
G01X-95632Y-64748D02*
X-99200Y-66412D01*
X-100184Y-66003D01*
X-101348Y-63505D01*
X-100458Y-60919D01*
X-99031Y-60253D01*
X-96477Y-61234D01*
X-95312Y-63732D01*
X-95632Y-64748D01*
G37*
G36*
G01X-99066Y-67007D02*
X-95536Y-65263D01*
X-94543Y-65650D01*
X-93323Y-68121D01*
X-94154Y-70727D01*
X-95566Y-71424D01*
X-98142Y-70501D01*
X-99362Y-68030D01*
X-99066Y-67007D01*
G37*
G36*
G01Y-81968D02*
X-95536Y-80224D01*
X-94543Y-80610D01*
X-93323Y-83081D01*
X-94154Y-85687D01*
X-95566Y-86385D01*
X-98142Y-85462D01*
X-99362Y-82991D01*
X-99066Y-81968D01*
G37*
G36*
G01X-95632Y-79708D02*
X-99200Y-81372D01*
X-100184Y-80964D01*
X-101348Y-78466D01*
X-100458Y-75879D01*
X-99031Y-75214D01*
X-96477Y-76194D01*
X-95312Y-78692D01*
X-95632Y-79708D01*
G37*
G36*
G01X-99066Y-96928D02*
X-95536Y-95185D01*
X-94543Y-95571D01*
X-93323Y-98042D01*
X-94154Y-100648D01*
X-95566Y-101346D01*
X-98142Y-100423D01*
X-99362Y-97952D01*
X-99066Y-96928D01*
G37*
G36*
G01X-95632Y-94669D02*
X-99200Y-96333D01*
X-100184Y-95924D01*
X-101348Y-93427D01*
X-100458Y-90840D01*
X-99031Y-90174D01*
X-96477Y-91155D01*
X-95312Y-93653D01*
X-95632Y-94669D01*
G37*
G36*
G01X-133515Y-52047D02*
X-129985Y-50303D01*
X-128992Y-50689D01*
X-127771Y-53160D01*
X-128603Y-55766D01*
X-130015Y-56464D01*
X-132590Y-55541D01*
X-133811Y-53070D01*
X-133515Y-52047D01*
G37*
G36*
G01X-130080Y-64748D02*
X-133649Y-66412D01*
X-134632Y-66003D01*
X-135797Y-63505D01*
X-134907Y-60919D01*
X-133479Y-60253D01*
X-130926Y-61234D01*
X-129761Y-63732D01*
X-130080Y-64748D01*
G37*
G36*
G01X-142373Y-52047D02*
X-138843Y-50303D01*
X-137850Y-50689D01*
X-136630Y-53160D01*
X-137461Y-55766D01*
X-138874Y-56464D01*
X-141449Y-55541D01*
X-142669Y-53070D01*
X-142373Y-52047D01*
G37*
G36*
G01X-133515Y-67007D02*
X-129985Y-65263D01*
X-128992Y-65650D01*
X-127771Y-68121D01*
X-128603Y-70727D01*
X-130015Y-71424D01*
X-132590Y-70501D01*
X-133811Y-68030D01*
X-133515Y-67007D01*
G37*
G36*
G01Y-81968D02*
X-129985Y-80224D01*
X-128992Y-80610D01*
X-127771Y-83081D01*
X-128603Y-85687D01*
X-130015Y-86385D01*
X-132590Y-85462D01*
X-133811Y-82991D01*
X-133515Y-81968D01*
G37*
G36*
G01X-130080Y-79708D02*
X-133649Y-81372D01*
X-134632Y-80964D01*
X-135797Y-78466D01*
X-134907Y-75879D01*
X-133479Y-75214D01*
X-130926Y-76194D01*
X-129761Y-78692D01*
X-130080Y-79708D01*
G37*
G36*
G01X-142373Y-81968D02*
X-138843Y-80224D01*
X-137850Y-80610D01*
X-136630Y-83081D01*
X-137461Y-85687D01*
X-138874Y-86385D01*
X-141449Y-85462D01*
X-142669Y-82991D01*
X-142373Y-81968D01*
G37*
G36*
G01Y-67007D02*
X-138843Y-65263D01*
X-137850Y-65650D01*
X-136630Y-68121D01*
X-137461Y-70727D01*
X-138874Y-71424D01*
X-141449Y-70501D01*
X-142669Y-68030D01*
X-142373Y-67007D01*
G37*
G36*
G01X-133515Y-96928D02*
X-129985Y-95185D01*
X-128992Y-95571D01*
X-127771Y-98042D01*
X-128603Y-100648D01*
X-130015Y-101346D01*
X-132590Y-100423D01*
X-133811Y-97952D01*
X-133515Y-96928D01*
G37*
G36*
G01X-130080Y-94669D02*
X-133649Y-96333D01*
X-134632Y-95924D01*
X-135797Y-93427D01*
X-134907Y-90840D01*
X-133479Y-90174D01*
X-130926Y-91155D01*
X-129761Y-93653D01*
X-130080Y-94669D01*
G37*
G36*
G01X-142373Y-96928D02*
X-138843Y-95185D01*
X-137850Y-95571D01*
X-136630Y-98042D01*
X-137461Y-100648D01*
X-138874Y-101346D01*
X-141449Y-100423D01*
X-142669Y-97952D01*
X-142373Y-96928D01*
G37*
G36*
G01X-138939Y-49787D02*
X-142507Y-51451D01*
X-143491Y-51043D01*
X-144655Y-48545D01*
X-143765Y-45958D01*
X-142338Y-45293D01*
X-139784Y-46273D01*
X-138619Y-48771D01*
X-138939Y-49787D01*
G37*
G36*
G01Y-64748D02*
X-142507Y-66412D01*
X-143491Y-66003D01*
X-144655Y-63505D01*
X-143765Y-60919D01*
X-142338Y-60253D01*
X-139784Y-61234D01*
X-138619Y-63732D01*
X-138939Y-64748D01*
G37*
G36*
G01Y-79708D02*
X-142507Y-81372D01*
X-143491Y-80964D01*
X-144655Y-78466D01*
X-143765Y-75879D01*
X-142338Y-75214D01*
X-139784Y-76194D01*
X-138619Y-78692D01*
X-138939Y-79708D01*
G37*
G36*
G01Y-94669D02*
X-142507Y-96333D01*
X-143491Y-95924D01*
X-144655Y-93427D01*
X-143765Y-90840D01*
X-142338Y-90174D01*
X-139784Y-91155D01*
X-138619Y-93653D01*
X-138939Y-94669D01*
G37*
G36*
G01X-229171Y-137850D02*
Y-146850D01*
X-230171Y-147850D01*
X-235571D01*
X-236571Y-146850D01*
Y-137850D01*
X-235571Y-136850D01*
X-230171D01*
X-229171Y-137850D01*
G37*
G36*
G01X-248069D02*
Y-146850D01*
X-249069Y-147850D01*
X-254469D01*
X-255469Y-146850D01*
Y-137850D01*
X-254469Y-136850D01*
X-249069D01*
X-248069Y-137850D01*
G37*
G36*
G01X-293268Y-80818D02*
Y-92362D01*
G02X-316654I-11693J0D01*
G01Y-80818D01*
G02X-293268I11693J12078D01*
G37*
G36*
G01X-549173Y-104441D02*
Y-115984D01*
G02X-572559I-11693J0D01*
G01Y-104441D01*
G02X-549173I11693J12078D01*
G37*
G36*
G01X-960286Y-52047D02*
X-956756Y-50303D01*
X-955764Y-50689D01*
X-954543Y-53160D01*
X-955375Y-55766D01*
X-956787Y-56464D01*
X-959362Y-55541D01*
X-960583Y-53070D01*
X-960286Y-52047D01*
G37*
G36*
G01X-956852Y-64748D02*
X-960420Y-66412D01*
X-961404Y-66003D01*
X-962569Y-63505D01*
X-961679Y-60919D01*
X-960251Y-60253D01*
X-957697Y-61234D01*
X-956533Y-63732D01*
X-956852Y-64748D01*
G37*
G36*
G01X-960286Y-67007D02*
X-956756Y-65263D01*
X-955764Y-65650D01*
X-954543Y-68121D01*
X-955375Y-70727D01*
X-956787Y-71424D01*
X-959362Y-70501D01*
X-960583Y-68030D01*
X-960286Y-67007D01*
G37*
G36*
G01Y-81968D02*
X-956756Y-80224D01*
X-955764Y-80610D01*
X-954543Y-83081D01*
X-955375Y-85687D01*
X-956787Y-86385D01*
X-959362Y-85462D01*
X-960583Y-82991D01*
X-960286Y-81968D01*
G37*
G36*
G01X-956852Y-79708D02*
X-960420Y-81372D01*
X-961404Y-80964D01*
X-962569Y-78466D01*
X-961679Y-75879D01*
X-960251Y-75214D01*
X-957697Y-76194D01*
X-956533Y-78692D01*
X-956852Y-79708D01*
G37*
G36*
G01X-960286Y-96928D02*
X-956756Y-95185D01*
X-955764Y-95571D01*
X-954543Y-98042D01*
X-955375Y-100648D01*
X-956787Y-101346D01*
X-959362Y-100423D01*
X-960583Y-97952D01*
X-960286Y-96928D01*
G37*
G36*
G01X-956852Y-94669D02*
X-960420Y-96333D01*
X-961404Y-95924D01*
X-962569Y-93427D01*
X-961679Y-90840D01*
X-960251Y-90174D01*
X-957697Y-91155D01*
X-956533Y-93653D01*
X-956852Y-94669D01*
G37*
G36*
G01X-965710Y-49787D02*
X-969279Y-51451D01*
X-970262Y-51043D01*
X-971427Y-48545D01*
X-970537Y-45958D01*
X-969109Y-45293D01*
X-966556Y-46273D01*
X-965391Y-48771D01*
X-965710Y-49787D01*
G37*
G36*
G01Y-64748D02*
X-969279Y-66412D01*
X-970262Y-66003D01*
X-971427Y-63505D01*
X-970537Y-60919D01*
X-969109Y-60253D01*
X-966556Y-61234D01*
X-965391Y-63732D01*
X-965710Y-64748D01*
G37*
G36*
G01X-969144Y-52047D02*
X-965615Y-50303D01*
X-964622Y-50689D01*
X-963401Y-53160D01*
X-964233Y-55766D01*
X-965645Y-56464D01*
X-968220Y-55541D01*
X-969441Y-53070D01*
X-969144Y-52047D01*
G37*
G36*
G01X-965710Y-79708D02*
X-969279Y-81372D01*
X-970262Y-80964D01*
X-971427Y-78466D01*
X-970537Y-75879D01*
X-969109Y-75214D01*
X-966556Y-76194D01*
X-965391Y-78692D01*
X-965710Y-79708D01*
G37*
G36*
G01X-969144Y-81968D02*
X-965615Y-80224D01*
X-964622Y-80610D01*
X-963401Y-83081D01*
X-964233Y-85687D01*
X-965645Y-86385D01*
X-968220Y-85462D01*
X-969441Y-82991D01*
X-969144Y-81968D01*
G37*
G36*
G01Y-67007D02*
X-965615Y-65263D01*
X-964622Y-65650D01*
X-963401Y-68121D01*
X-964233Y-70727D01*
X-965645Y-71424D01*
X-968220Y-70501D01*
X-969441Y-68030D01*
X-969144Y-67007D01*
G37*
G36*
G01X-965710Y-94669D02*
X-969279Y-96333D01*
X-970262Y-95924D01*
X-971427Y-93427D01*
X-970537Y-90840D01*
X-969109Y-90174D01*
X-966556Y-91155D01*
X-965391Y-93653D01*
X-965710Y-94669D01*
G37*
G36*
G01X-969144Y-96928D02*
X-965615Y-95185D01*
X-964622Y-95571D01*
X-963401Y-98042D01*
X-964233Y-100648D01*
X-965645Y-101346D01*
X-968220Y-100423D01*
X-969441Y-97952D01*
X-969144Y-96928D01*
G37*
G36*
G01X-1000159Y-64748D02*
X-1003727Y-66412D01*
X-1004711Y-66003D01*
X-1005876Y-63505D01*
X-1004986Y-60919D01*
X-1003558Y-60253D01*
X-1001004Y-61234D01*
X-999840Y-63732D01*
X-1000159Y-64748D01*
G37*
G36*
G01X-1003593Y-52047D02*
X-1000064Y-50303D01*
X-999071Y-50689D01*
X-997850Y-53160D01*
X-998682Y-55766D01*
X-1000094Y-56464D01*
X-1002669Y-55541D01*
X-1003890Y-53070D01*
X-1003593Y-52047D01*
G37*
G36*
G01X-1000159Y-79708D02*
X-1003727Y-81372D01*
X-1004711Y-80964D01*
X-1005876Y-78466D01*
X-1004986Y-75879D01*
X-1003558Y-75214D01*
X-1001004Y-76194D01*
X-999840Y-78692D01*
X-1000159Y-79708D01*
G37*
G36*
G01X-1003593Y-81968D02*
X-1000064Y-80224D01*
X-999071Y-80610D01*
X-997850Y-83081D01*
X-998682Y-85687D01*
X-1000094Y-86385D01*
X-1002669Y-85462D01*
X-1003890Y-82991D01*
X-1003593Y-81968D01*
G37*
G36*
G01Y-67007D02*
X-1000064Y-65263D01*
X-999071Y-65650D01*
X-997850Y-68121D01*
X-998682Y-70727D01*
X-1000094Y-71424D01*
X-1002669Y-70501D01*
X-1003890Y-68030D01*
X-1003593Y-67007D01*
G37*
G36*
G01X-1000159Y-94669D02*
X-1003727Y-96333D01*
X-1004711Y-95924D01*
X-1005876Y-93427D01*
X-1004986Y-90840D01*
X-1003558Y-90174D01*
X-1001004Y-91155D01*
X-999840Y-93653D01*
X-1000159Y-94669D01*
G37*
G36*
G01X-1003593Y-96928D02*
X-1000064Y-95185D01*
X-999071Y-95571D01*
X-997850Y-98042D01*
X-998682Y-100648D01*
X-1000094Y-101346D01*
X-1002669Y-100423D01*
X-1003890Y-97952D01*
X-1003593Y-96928D01*
G37*
G36*
G01X-1009017Y-49787D02*
X-1012586Y-51451D01*
X-1013569Y-51043D01*
X-1014734Y-48545D01*
X-1013844Y-45958D01*
X-1012416Y-45293D01*
X-1009863Y-46273D01*
X-1008698Y-48771D01*
X-1009017Y-49787D01*
G37*
G36*
G01Y-64748D02*
X-1012586Y-66412D01*
X-1013569Y-66003D01*
X-1014734Y-63505D01*
X-1013844Y-60919D01*
X-1012416Y-60253D01*
X-1009863Y-61234D01*
X-1008698Y-63732D01*
X-1009017Y-64748D01*
G37*
G36*
G01X-1012452Y-52047D02*
X-1008922Y-50303D01*
X-1007929Y-50689D01*
X-1006708Y-53160D01*
X-1007540Y-55766D01*
X-1008952Y-56464D01*
X-1011527Y-55541D01*
X-1012748Y-53070D01*
X-1012452Y-52047D01*
G37*
G36*
G01Y-67007D02*
X-1008922Y-65263D01*
X-1007929Y-65650D01*
X-1006708Y-68121D01*
X-1007540Y-70727D01*
X-1008952Y-71424D01*
X-1011527Y-70501D01*
X-1012748Y-68030D01*
X-1012452Y-67007D01*
G37*
G36*
G01Y-81968D02*
X-1008922Y-80224D01*
X-1007929Y-80610D01*
X-1006708Y-83081D01*
X-1007540Y-85687D01*
X-1008952Y-86385D01*
X-1011527Y-85462D01*
X-1012748Y-82991D01*
X-1012452Y-81968D01*
G37*
G36*
G01X-1009017Y-79708D02*
X-1012586Y-81372D01*
X-1013569Y-80964D01*
X-1014734Y-78466D01*
X-1013844Y-75879D01*
X-1012416Y-75214D01*
X-1009863Y-76194D01*
X-1008698Y-78692D01*
X-1009017Y-79708D01*
G37*
G36*
G01X-1012452Y-96928D02*
X-1008922Y-95185D01*
X-1007929Y-95571D01*
X-1006708Y-98042D01*
X-1007540Y-100648D01*
X-1008952Y-101346D01*
X-1011527Y-100423D01*
X-1012748Y-97952D01*
X-1012452Y-96928D01*
G37*
G36*
G01X-1009017Y-94669D02*
X-1012586Y-96333D01*
X-1013569Y-95924D01*
X-1014734Y-93427D01*
X-1013844Y-90840D01*
X-1012416Y-90174D01*
X-1009863Y-91155D01*
X-1008698Y-93653D01*
X-1009017Y-94669D01*
G37*
G36*
G01X-1099250Y-137850D02*
Y-146850D01*
X-1100250Y-147850D01*
X-1105650D01*
X-1106650Y-146850D01*
Y-137850D01*
X-1105650Y-136850D01*
X-1100250D01*
X-1099250Y-137850D01*
G37*
G36*
G01X-1118148D02*
Y-146850D01*
X-1119148Y-147850D01*
X-1124548D01*
X-1125548Y-146850D01*
Y-137850D01*
X-1124548Y-136850D01*
X-1119148D01*
X-1118148Y-137850D01*
G37*
G36*
G01X-1167283Y-80818D02*
Y-92362D01*
G02X-1190669I-11693J0D01*
G01Y-80818D01*
G02X-1167283I11693J12078D01*
G37*
G36*
G01X-1411378Y-134126D02*
Y-145669D01*
G02X-1434764I-11693J0D01*
G01Y-134126D01*
G02X-1411378I11693J12078D01*
G37*
G36*
G01X-1631850Y-63259D02*
Y-74803D01*
G02X-1655236I-11693J0D01*
G01Y-63259D01*
G02X-1631850I11693J12078D01*
G37*
G36*
G01X-593212Y-86800D02*
X-593211Y-86793D01*
Y-81986D01*
X-593212Y-81979D01*
G02X-590029Y-81674I1598J90D01*
G01X-590011Y-81803D01*
Y-86977D01*
X-590029Y-87106D01*
G02X-593212Y-86800I-1585J216D01*
G37*
G36*
G01X-603212D02*
X-603211Y-86793D01*
Y-81986D01*
X-603212Y-81979D01*
G02X-600029Y-81674I1598J90D01*
G01X-600011Y-81803D01*
Y-86977D01*
X-600029Y-87106D01*
G02X-603212Y-86800I-1585J216D01*
G37*
G36*
G01X-613212D02*
X-613211Y-86793D01*
Y-81986D01*
X-613212Y-81979D01*
G02X-610029Y-81674I1598J90D01*
G01X-610011Y-81803D01*
Y-86977D01*
X-610029Y-87106D01*
G02X-613212Y-86800I-1585J216D01*
G37*
G36*
G01X-1463290D02*
X-1463290Y-86793D01*
Y-81986D01*
X-1463290Y-81979D01*
G02X-1460108Y-81674I1598J90D01*
G01X-1460090Y-81803D01*
Y-86977D01*
X-1460108Y-87106D01*
G02X-1463290Y-86800I-1585J216D01*
G37*
G36*
G01X-1473290D02*
X-1473290Y-86793D01*
Y-81986D01*
X-1473290Y-81979D01*
G02X-1470108Y-81674I1598J90D01*
G01X-1470090Y-81803D01*
Y-86977D01*
X-1470108Y-87106D01*
G02X-1473290Y-86800I-1585J216D01*
G37*
G36*
G01X-1483290D02*
X-1483290Y-86793D01*
Y-81986D01*
X-1483290Y-81979D01*
G02X-1480108Y-81674I1598J90D01*
G01X-1480090Y-81803D01*
Y-86977D01*
X-1480108Y-87106D01*
G02X-1483290Y-86800I-1585J216D01*
G37*
G36*
G01X-598212Y-96800D02*
X-598211Y-96793D01*
Y-91986D01*
X-598212Y-91979D01*
G02X-595029Y-91674I1598J90D01*
G01X-595011Y-91803D01*
Y-96977D01*
X-595029Y-97106D01*
G02X-598212Y-96800I-1585J216D01*
G37*
G36*
G01X-608212D02*
X-608211Y-96793D01*
Y-91986D01*
X-608212Y-91979D01*
G02X-605029Y-91674I1598J90D01*
G01X-605011Y-91803D01*
Y-96977D01*
X-605029Y-97106D01*
G02X-608212Y-96800I-1585J216D01*
G37*
G36*
G01X-618212D02*
X-618211Y-96793D01*
Y-91986D01*
X-618212Y-91979D01*
G02X-615029Y-91674I1598J90D01*
G01X-615011Y-91803D01*
Y-96977D01*
X-615029Y-97106D01*
G02X-618212Y-96800I-1585J216D01*
G37*
G36*
G01X-1468290D02*
X-1468290Y-96793D01*
Y-91986D01*
X-1468290Y-91979D01*
G02X-1465108Y-91674I1598J90D01*
G01X-1465090Y-91803D01*
Y-96977D01*
X-1465108Y-97106D01*
G02X-1468290Y-96800I-1585J216D01*
G37*
G36*
G01X-1478290D02*
X-1478290Y-96793D01*
Y-91986D01*
X-1478290Y-91979D01*
G02X-1475108Y-91674I1598J90D01*
G01X-1475090Y-91803D01*
Y-96977D01*
X-1475108Y-97106D01*
G02X-1478290Y-96800I-1585J216D01*
G37*
G36*
G01X-1488290D02*
X-1488290Y-96793D01*
Y-91986D01*
X-1488290Y-91979D01*
G02X-1485108Y-91674I1598J90D01*
G01X-1485090Y-91803D01*
Y-96977D01*
X-1485108Y-97106D01*
G02X-1488290Y-96800I-1585J216D01*
G37*
G36*
G01X-593212Y-106800D02*
X-593211Y-106793D01*
Y-101986D01*
X-593212Y-101979D01*
G02X-590029Y-101674I1598J90D01*
G01X-590011Y-101803D01*
Y-106977D01*
X-590029Y-107106D01*
G02X-593212Y-106800I-1585J216D01*
G37*
G36*
G01X-603212D02*
X-603211Y-106793D01*
Y-101986D01*
X-603212Y-101979D01*
G02X-600029Y-101674I1598J90D01*
G01X-600011Y-101803D01*
Y-106977D01*
X-600029Y-107106D01*
G02X-603212Y-106800I-1585J216D01*
G37*
G36*
G01X-613212D02*
X-613211Y-106793D01*
Y-101986D01*
X-613212Y-101979D01*
G02X-610029Y-101674I1598J90D01*
G01X-610011Y-101803D01*
Y-106977D01*
X-610029Y-107106D01*
G02X-613212Y-106800I-1585J216D01*
G37*
G36*
G01X-1463290D02*
X-1463290Y-106793D01*
Y-101986D01*
X-1463290Y-101979D01*
G02X-1460108Y-101674I1598J90D01*
G01X-1460090Y-101803D01*
Y-106977D01*
X-1460108Y-107106D01*
G02X-1463290Y-106800I-1585J216D01*
G37*
G36*
G01X-1473290D02*
X-1473290Y-106793D01*
Y-101986D01*
X-1473290Y-101979D01*
G02X-1470108Y-101674I1598J90D01*
G01X-1470090Y-101803D01*
Y-106977D01*
X-1470108Y-107106D01*
G02X-1473290Y-106800I-1585J216D01*
G37*
G36*
G01X-1483290D02*
X-1483290Y-106793D01*
Y-101986D01*
X-1483290Y-101979D01*
G02X-1480108Y-101674I1598J90D01*
G01X-1480090Y-101803D01*
Y-106977D01*
X-1480108Y-107106D01*
G02X-1483290Y-106800I-1585J216D01*
G37*
G36*
G01X-680665Y-108132D02*
Y-110173D01*
X-685165D01*
Y-108126D01*
G02Y-105732I2252J1197D01*
G01Y-102614D01*
G02Y-100221I2252J1197D01*
G01Y-98173D01*
X-680665D01*
Y-100214D01*
G02Y-102621I-2248J-1203D01*
G01Y-105726D01*
G02Y-108132I-2248J-1203D01*
G37*
G36*
G01X-696413D02*
Y-110173D01*
X-700913D01*
Y-108126D01*
G02Y-105732I2252J1197D01*
G01Y-102614D01*
G02Y-100221I2252J1197D01*
G01Y-98173D01*
X-696413D01*
Y-100214D01*
G02Y-102621I-2248J-1203D01*
G01Y-105726D01*
G02Y-108132I-2248J-1203D01*
G37*
G36*
G01X-712161D02*
Y-110173D01*
X-716661D01*
Y-108126D01*
G02Y-105732I2252J1197D01*
G01Y-102614D01*
G02Y-100221I2252J1197D01*
G01Y-98173D01*
X-712161D01*
Y-100214D01*
G02Y-102621I-2248J-1203D01*
G01Y-105726D01*
G02Y-108132I-2248J-1203D01*
G37*
G36*
G01X-727909D02*
Y-110173D01*
X-732409D01*
Y-108126D01*
G02Y-105732I2252J1197D01*
G01Y-102614D01*
G02Y-100221I2252J1197D01*
G01Y-98173D01*
X-727909D01*
Y-100214D01*
G02Y-102621I-2248J-1203D01*
G01Y-105726D01*
G02Y-108132I-2248J-1203D01*
G37*
G36*
G01X-1550744D02*
Y-110173D01*
X-1555244D01*
Y-108126D01*
G02Y-105732I2252J1197D01*
G01Y-102614D01*
G02Y-100221I2252J1197D01*
G01Y-98173D01*
X-1550744D01*
Y-100214D01*
G02Y-102621I-2248J-1203D01*
G01Y-105726D01*
G02Y-108132I-2248J-1203D01*
G37*
G36*
G01X-1566492D02*
Y-110173D01*
X-1570992D01*
Y-108126D01*
G02Y-105732I2252J1197D01*
G01Y-102614D01*
G02Y-100221I2252J1197D01*
G01Y-98173D01*
X-1566492D01*
Y-100214D01*
G02Y-102621I-2248J-1203D01*
G01Y-105726D01*
G02Y-108132I-2248J-1203D01*
G37*
G36*
G01X-1582240D02*
Y-110173D01*
X-1586740D01*
Y-108126D01*
G02Y-105732I2252J1197D01*
G01Y-102614D01*
G02Y-100221I2252J1197D01*
G01Y-98173D01*
X-1582240D01*
Y-100214D01*
G02Y-102621I-2248J-1203D01*
G01Y-105726D01*
G02Y-108132I-2248J-1203D01*
G37*
G36*
G01X-1597988D02*
Y-110173D01*
X-1602488D01*
Y-108126D01*
G02Y-105732I2252J1197D01*
G01Y-102614D01*
G02Y-100221I2252J1197D01*
G01Y-98173D01*
X-1597988D01*
Y-100214D01*
G02Y-102621I-2248J-1203D01*
G01Y-105726D01*
G02Y-108132I-2248J-1203D01*
G37*
G36*
G01X-672791Y-113250D02*
Y-115291D01*
X-677291D01*
Y-113244D01*
G02Y-110850I2252J1197D01*
G01Y-107732D01*
G02Y-105339I2252J1197D01*
G01Y-103291D01*
X-672791D01*
Y-105332D01*
G02Y-107739I-2248J-1203D01*
G01Y-110844D01*
G02Y-113250I-2248J-1203D01*
G37*
G36*
G01X-688539D02*
Y-115291D01*
X-693039D01*
Y-113244D01*
G02Y-110850I2252J1197D01*
G01Y-107732D01*
G02Y-105339I2252J1197D01*
G01Y-103291D01*
X-688539D01*
Y-105332D01*
G02Y-107739I-2248J-1203D01*
G01Y-110844D01*
G02Y-113250I-2248J-1203D01*
G37*
G36*
G01X-704287D02*
Y-115291D01*
X-708787D01*
Y-113244D01*
G02Y-110850I2252J1197D01*
G01Y-107732D01*
G02Y-105339I2252J1197D01*
G01Y-103291D01*
X-704287D01*
Y-105332D01*
G02Y-107739I-2248J-1203D01*
G01Y-110844D01*
G02Y-113250I-2248J-1203D01*
G37*
G36*
G01X-720035D02*
Y-115291D01*
X-724535D01*
Y-113244D01*
G02Y-110850I2252J1197D01*
G01Y-107732D01*
G02Y-105339I2252J1197D01*
G01Y-103291D01*
X-720035D01*
Y-105332D01*
G02Y-107739I-2248J-1203D01*
G01Y-110844D01*
G02Y-113250I-2248J-1203D01*
G37*
G36*
G01X-1542870D02*
Y-115291D01*
X-1547370D01*
Y-113244D01*
G02Y-110850I2252J1197D01*
G01Y-107732D01*
G02Y-105339I2252J1197D01*
G01Y-103291D01*
X-1542870D01*
Y-105332D01*
G02Y-107739I-2248J-1203D01*
G01Y-110844D01*
G02Y-113250I-2248J-1203D01*
G37*
G36*
G01X-1558618D02*
Y-115291D01*
X-1563118D01*
Y-113244D01*
G02Y-110850I2252J1197D01*
G01Y-107732D01*
G02Y-105339I2252J1197D01*
G01Y-103291D01*
X-1558618D01*
Y-105332D01*
G02Y-107739I-2248J-1203D01*
G01Y-110844D01*
G02Y-113250I-2248J-1203D01*
G37*
G36*
G01X-1574366D02*
Y-115291D01*
X-1578866D01*
Y-113244D01*
G02Y-110850I2252J1197D01*
G01Y-107732D01*
G02Y-105339I2252J1197D01*
G01Y-103291D01*
X-1574366D01*
Y-105332D01*
G02Y-107739I-2248J-1203D01*
G01Y-110844D01*
G02Y-113250I-2248J-1203D01*
G37*
G36*
G01X-1590114D02*
Y-115291D01*
X-1594614D01*
Y-113244D01*
G02Y-110850I2252J1197D01*
G01Y-107732D01*
G02Y-105339I2252J1197D01*
G01Y-103291D01*
X-1590114D01*
Y-105332D01*
G02Y-107739I-2248J-1203D01*
G01Y-110844D01*
G02Y-113250I-2248J-1203D01*
G37*
G36*
G01X-598212Y-116800D02*
X-598211Y-116793D01*
Y-111986D01*
X-598212Y-111979D01*
G02X-595029Y-111674I1598J90D01*
G01X-595011Y-111803D01*
Y-116977D01*
X-595029Y-117106D01*
G02X-598212Y-116800I-1585J216D01*
G37*
G36*
G01X-608212D02*
X-608211Y-116793D01*
Y-111986D01*
X-608212Y-111979D01*
G02X-605029Y-111674I1598J90D01*
G01X-605011Y-111803D01*
Y-116977D01*
X-605029Y-117106D01*
G02X-608212Y-116800I-1585J216D01*
G37*
G36*
G01X-618212D02*
X-618211Y-116793D01*
Y-111986D01*
X-618212Y-111979D01*
G02X-615029Y-111674I1598J90D01*
G01X-615011Y-111803D01*
Y-116977D01*
X-615029Y-117106D01*
G02X-618212Y-116800I-1585J216D01*
G37*
G36*
G01X-1468290D02*
X-1468290Y-116793D01*
Y-111986D01*
X-1468290Y-111979D01*
G02X-1465108Y-111674I1598J90D01*
G01X-1465090Y-111803D01*
Y-116977D01*
X-1465108Y-117106D01*
G02X-1468290Y-116800I-1585J216D01*
G37*
G36*
G01X-1478290D02*
X-1478290Y-116793D01*
Y-111986D01*
X-1478290Y-111979D01*
G02X-1475108Y-111674I1598J90D01*
G01X-1475090Y-111803D01*
Y-116977D01*
X-1475108Y-117106D01*
G02X-1478290Y-116800I-1585J216D01*
G37*
G36*
G01X-1488290D02*
X-1488290Y-116793D01*
Y-111986D01*
X-1488290Y-111979D01*
G02X-1485108Y-111674I1598J90D01*
G01X-1485090Y-111803D01*
Y-116977D01*
X-1485108Y-117106D01*
G02X-1488290Y-116800I-1585J216D01*
G37*
G36*
G01X-240725Y-121879D02*
X-240744Y-121702D01*
Y-118409D01*
X-240725Y-118232D01*
G02X-236543Y-118618I2088J-223D01*
G01X-236544Y-118627D01*
Y-121483D01*
X-236543Y-121493D01*
G02X-240725Y-121879I-2094J-162D01*
G37*
G36*
G01X-1110804D02*
X-1110823Y-121702D01*
Y-118409D01*
X-1110804Y-118232D01*
G02X-1106622Y-118618I2088J-223D01*
G01X-1106623Y-118627D01*
Y-121483D01*
X-1106622Y-121493D01*
G02X-1110804Y-121879I-2094J-162D01*
G37*
G36*
G01X-680665Y-124668D02*
Y-126709D01*
X-685165D01*
Y-124661D01*
G02Y-122268I2252J1197D01*
G01Y-119150D01*
G02Y-116756I2252J1197D01*
G01Y-114709D01*
X-680665D01*
Y-116750D01*
G02Y-119156I-2248J-1203D01*
G01Y-122261D01*
G02Y-124668I-2248J-1203D01*
G37*
G36*
G01X-696413D02*
Y-126709D01*
X-700913D01*
Y-124661D01*
G02Y-122268I2252J1197D01*
G01Y-119150D01*
G02Y-116756I2252J1197D01*
G01Y-114709D01*
X-696413D01*
Y-116750D01*
G02Y-119156I-2248J-1203D01*
G01Y-122261D01*
G02Y-124668I-2248J-1203D01*
G37*
G36*
G01X-712161D02*
Y-126709D01*
X-716661D01*
Y-124661D01*
G02Y-122268I2252J1197D01*
G01Y-119150D01*
G02Y-116756I2252J1197D01*
G01Y-114709D01*
X-712161D01*
Y-116750D01*
G02Y-119156I-2248J-1203D01*
G01Y-122261D01*
G02Y-124668I-2248J-1203D01*
G37*
G36*
G01X-727909D02*
Y-126709D01*
X-732409D01*
Y-124661D01*
G02Y-122268I2252J1197D01*
G01Y-119150D01*
G02Y-116756I2252J1197D01*
G01Y-114709D01*
X-727909D01*
Y-116750D01*
G02Y-119156I-2248J-1203D01*
G01Y-122261D01*
G02Y-124668I-2248J-1203D01*
G37*
G36*
G01X-1550744D02*
Y-126709D01*
X-1555244D01*
Y-124661D01*
G02Y-122268I2252J1197D01*
G01Y-119150D01*
G02Y-116756I2252J1197D01*
G01Y-114709D01*
X-1550744D01*
Y-116750D01*
G02Y-119156I-2248J-1203D01*
G01Y-122261D01*
G02Y-124668I-2248J-1203D01*
G37*
G36*
G01X-1566492D02*
Y-126709D01*
X-1570992D01*
Y-124661D01*
G02Y-122268I2252J1197D01*
G01Y-119150D01*
G02Y-116756I2252J1197D01*
G01Y-114709D01*
X-1566492D01*
Y-116750D01*
G02Y-119156I-2248J-1203D01*
G01Y-122261D01*
G02Y-124668I-2248J-1203D01*
G37*
G36*
G01X-1582240D02*
Y-126709D01*
X-1586740D01*
Y-124661D01*
G02Y-122268I2252J1197D01*
G01Y-119150D01*
G02Y-116756I2252J1197D01*
G01Y-114709D01*
X-1582240D01*
Y-116750D01*
G02Y-119156I-2248J-1203D01*
G01Y-122261D01*
G02Y-124668I-2248J-1203D01*
G37*
G36*
G01X-1597988D02*
Y-126709D01*
X-1602488D01*
Y-124661D01*
G02Y-122268I2252J1197D01*
G01Y-119150D01*
G02Y-116756I2252J1197D01*
G01Y-114709D01*
X-1597988D01*
Y-116750D01*
G02Y-119156I-2248J-1203D01*
G01Y-122261D01*
G02Y-124668I-2248J-1203D01*
G37*
G36*
G01X-1347998Y-116208D02*
G02X-1347689Y-120301I-8891J-2729D01*
G02X-1347998Y-116208I-9199J1364D01*
G37*
G36*
G01X-593212Y-126800D02*
X-593211Y-126793D01*
Y-121986D01*
X-593212Y-121979D01*
G02X-590029Y-121674I1598J90D01*
G01X-590011Y-121803D01*
Y-126977D01*
X-590029Y-127106D01*
G02X-593212Y-126800I-1585J216D01*
G37*
G36*
G01X-603212D02*
X-603211Y-126793D01*
Y-121986D01*
X-603212Y-121979D01*
G02X-600029Y-121674I1598J90D01*
G01X-600011Y-121803D01*
Y-126977D01*
X-600029Y-127106D01*
G02X-603212Y-126800I-1585J216D01*
G37*
G36*
G01X-613212D02*
X-613211Y-126793D01*
Y-121986D01*
X-613212Y-121979D01*
G02X-610029Y-121674I1598J90D01*
G01X-610011Y-121803D01*
Y-126977D01*
X-610029Y-127106D01*
G02X-613212Y-126800I-1585J216D01*
G37*
G36*
G01X-1463290D02*
X-1463290Y-126793D01*
Y-121986D01*
X-1463290Y-121979D01*
G02X-1460108Y-121674I1598J90D01*
G01X-1460090Y-121803D01*
Y-126977D01*
X-1460108Y-127106D01*
G02X-1463290Y-126800I-1585J216D01*
G37*
G36*
G01X-1473290D02*
X-1473290Y-126793D01*
Y-121986D01*
X-1473290Y-121979D01*
G02X-1470108Y-121674I1598J90D01*
G01X-1470090Y-121803D01*
Y-126977D01*
X-1470108Y-127106D01*
G02X-1473290Y-126800I-1585J216D01*
G37*
G36*
G01X-1483290D02*
X-1483290Y-126793D01*
Y-121986D01*
X-1483290Y-121979D01*
G02X-1480108Y-121674I1598J90D01*
G01X-1480090Y-121803D01*
Y-126977D01*
X-1480108Y-127106D01*
G02X-1483290Y-126800I-1585J216D01*
G37*
G36*
G01X-672791Y-129786D02*
Y-131827D01*
X-677291D01*
Y-129779D01*
G02Y-127386I2252J1197D01*
G01Y-124268D01*
G02Y-121874I2252J1197D01*
G01Y-119827D01*
X-672791D01*
Y-121868D01*
G02Y-124274I-2248J-1203D01*
G01Y-127379D01*
G02Y-129786I-2248J-1203D01*
G37*
G36*
G01X-688539D02*
Y-131827D01*
X-693039D01*
Y-129779D01*
G02Y-127386I2252J1197D01*
G01Y-124268D01*
G02Y-121874I2252J1197D01*
G01Y-119827D01*
X-688539D01*
Y-121868D01*
G02Y-124274I-2248J-1203D01*
G01Y-127379D01*
G02Y-129786I-2248J-1203D01*
G37*
G36*
G01X-704287D02*
Y-131827D01*
X-708787D01*
Y-129779D01*
G02Y-127386I2252J1197D01*
G01Y-124268D01*
G02Y-121874I2252J1197D01*
G01Y-119827D01*
X-704287D01*
Y-121868D01*
G02Y-124274I-2248J-1203D01*
G01Y-127379D01*
G02Y-129786I-2248J-1203D01*
G37*
G36*
G01X-720035D02*
Y-131827D01*
X-724535D01*
Y-129779D01*
G02Y-127386I2252J1197D01*
G01Y-124268D01*
G02Y-121874I2252J1197D01*
G01Y-119827D01*
X-720035D01*
Y-121868D01*
G02Y-124274I-2248J-1203D01*
G01Y-127379D01*
G02Y-129786I-2248J-1203D01*
G37*
G36*
G01X-735783D02*
Y-131827D01*
X-740283D01*
Y-129779D01*
G02Y-127386I2252J1197D01*
G01Y-124268D01*
G02Y-121874I2252J1197D01*
G01Y-119827D01*
X-735783D01*
Y-121868D01*
G02Y-124274I-2248J-1203D01*
G01Y-127379D01*
G02Y-129786I-2248J-1203D01*
G37*
G36*
G01X-1542870D02*
Y-131827D01*
X-1547370D01*
Y-129779D01*
G02Y-127386I2252J1197D01*
G01Y-124268D01*
G02Y-121874I2252J1197D01*
G01Y-119827D01*
X-1542870D01*
Y-121868D01*
G02Y-124274I-2248J-1203D01*
G01Y-127379D01*
G02Y-129786I-2248J-1203D01*
G37*
G36*
G01X-1558618D02*
Y-131827D01*
X-1563118D01*
Y-129779D01*
G02Y-127386I2252J1197D01*
G01Y-124268D01*
G02Y-121874I2252J1197D01*
G01Y-119827D01*
X-1558618D01*
Y-121868D01*
G02Y-124274I-2248J-1203D01*
G01Y-127379D01*
G02Y-129786I-2248J-1203D01*
G37*
G36*
G01X-1574366D02*
Y-131827D01*
X-1578866D01*
Y-129779D01*
G02Y-127386I2252J1197D01*
G01Y-124268D01*
G02Y-121874I2252J1197D01*
G01Y-119827D01*
X-1574366D01*
Y-121868D01*
G02Y-124274I-2248J-1203D01*
G01Y-127379D01*
G02Y-129786I-2248J-1203D01*
G37*
G36*
G01X-1590114D02*
Y-131827D01*
X-1594614D01*
Y-129779D01*
G02Y-127386I2252J1197D01*
G01Y-124268D01*
G02Y-121874I2252J1197D01*
G01Y-119827D01*
X-1590114D01*
Y-121868D01*
G02Y-124274I-2248J-1203D01*
G01Y-127379D01*
G02Y-129786I-2248J-1203D01*
G37*
G36*
G01X-1605862D02*
Y-131827D01*
X-1610362D01*
Y-129779D01*
G02Y-127386I2252J1197D01*
G01Y-124268D01*
G02Y-121874I2252J1197D01*
G01Y-119827D01*
X-1605862D01*
Y-121868D01*
G02Y-124274I-2248J-1203D01*
G01Y-127379D01*
G02Y-129786I-2248J-1203D01*
G37*
G36*
G01X-363438Y-132269D02*
X-363260Y-132250D01*
X-359968D01*
X-359791Y-132269D01*
G02X-360176Y-136451I-223J-2088D01*
G01X-360186Y-136450D01*
X-363042D01*
X-363051Y-136451D01*
G02X-363438Y-132269I-162J2094D01*
G37*
G36*
G01X-1233516D02*
X-1233339Y-132250D01*
X-1230046D01*
X-1229869Y-132269D01*
G02X-1230255Y-136451I-223J-2088D01*
G01X-1230264Y-136450D01*
X-1233121D01*
X-1233130Y-136451D01*
G02X-1233516Y-132269I-162J2094D01*
G37*
G36*
G01X-598212Y-136800D02*
X-598211Y-136793D01*
Y-131986D01*
X-598212Y-131979D01*
G02X-595029Y-131674I1598J90D01*
G01X-595011Y-131803D01*
Y-136977D01*
X-595029Y-137106D01*
G02X-598212Y-136800I-1585J216D01*
G37*
G36*
G01X-608212D02*
X-608211Y-136793D01*
Y-131986D01*
X-608212Y-131979D01*
G02X-605029Y-131674I1598J90D01*
G01X-605011Y-131803D01*
Y-136977D01*
X-605029Y-137106D01*
G02X-608212Y-136800I-1585J216D01*
G37*
G36*
G01X-618212D02*
X-618211Y-136793D01*
Y-131986D01*
X-618212Y-131979D01*
G02X-615029Y-131674I1598J90D01*
G01X-615011Y-131803D01*
Y-136977D01*
X-615029Y-137106D01*
G02X-618212Y-136800I-1585J216D01*
G37*
G36*
G01X-1468290D02*
X-1468290Y-136793D01*
Y-131986D01*
X-1468290Y-131979D01*
G02X-1465108Y-131674I1598J90D01*
G01X-1465090Y-131803D01*
Y-136977D01*
X-1465108Y-137106D01*
G02X-1468290Y-136800I-1585J216D01*
G37*
G36*
G01X-1478290D02*
X-1478290Y-136793D01*
Y-131986D01*
X-1478290Y-131979D01*
G02X-1475108Y-131674I1598J90D01*
G01X-1475090Y-131803D01*
Y-136977D01*
X-1475108Y-137106D01*
G02X-1478290Y-136800I-1585J216D01*
G37*
G36*
G01X-1488290D02*
X-1488290Y-136793D01*
Y-131986D01*
X-1488290Y-131979D01*
G02X-1485108Y-131674I1598J90D01*
G01X-1485090Y-131803D01*
Y-136977D01*
X-1485108Y-137106D01*
G02X-1488290Y-136800I-1585J216D01*
G37*
G36*
G01X-680665Y-141203D02*
Y-143244D01*
X-685165D01*
Y-141197D01*
G02Y-138803I2252J1197D01*
G01Y-135685D01*
G02Y-133291I2252J1197D01*
G01Y-131244D01*
X-680665D01*
Y-133285D01*
G02Y-135691I-2248J-1203D01*
G01Y-138797D01*
G02Y-141203I-2248J-1203D01*
G37*
G36*
G01X-696413D02*
Y-143244D01*
X-700913D01*
Y-141197D01*
G02Y-138803I2252J1197D01*
G01Y-135685D01*
G02Y-133291I2252J1197D01*
G01Y-131244D01*
X-696413D01*
Y-133285D01*
G02Y-135691I-2248J-1203D01*
G01Y-138797D01*
G02Y-141203I-2248J-1203D01*
G37*
G36*
G01X-712161D02*
Y-143244D01*
X-716661D01*
Y-141197D01*
G02Y-138803I2252J1197D01*
G01Y-135685D01*
G02Y-133291I2252J1197D01*
G01Y-131244D01*
X-712161D01*
Y-133285D01*
G02Y-135691I-2248J-1203D01*
G01Y-138797D01*
G02Y-141203I-2248J-1203D01*
G37*
G36*
G01X-727909D02*
Y-143244D01*
X-732409D01*
Y-141197D01*
G02Y-138803I2252J1197D01*
G01Y-135685D01*
G02Y-133291I2252J1197D01*
G01Y-131244D01*
X-727909D01*
Y-133285D01*
G02Y-135691I-2248J-1203D01*
G01Y-138797D01*
G02Y-141203I-2248J-1203D01*
G37*
G36*
G01X-1550744D02*
Y-143244D01*
X-1555244D01*
Y-141197D01*
G02Y-138803I2252J1197D01*
G01Y-135685D01*
G02Y-133291I2252J1197D01*
G01Y-131244D01*
X-1550744D01*
Y-133285D01*
G02Y-135691I-2248J-1203D01*
G01Y-138797D01*
G02Y-141203I-2248J-1203D01*
G37*
G36*
G01X-1566492D02*
Y-143244D01*
X-1570992D01*
Y-141197D01*
G02Y-138803I2252J1197D01*
G01Y-135685D01*
G02Y-133291I2252J1197D01*
G01Y-131244D01*
X-1566492D01*
Y-133285D01*
G02Y-135691I-2248J-1203D01*
G01Y-138797D01*
G02Y-141203I-2248J-1203D01*
G37*
G36*
G01X-1582240D02*
Y-143244D01*
X-1586740D01*
Y-141197D01*
G02Y-138803I2252J1197D01*
G01Y-135685D01*
G02Y-133291I2252J1197D01*
G01Y-131244D01*
X-1582240D01*
Y-133285D01*
G02Y-135691I-2248J-1203D01*
G01Y-138797D01*
G02Y-141203I-2248J-1203D01*
G37*
G36*
G01X-1597988D02*
Y-143244D01*
X-1602488D01*
Y-141197D01*
G02Y-138803I2252J1197D01*
G01Y-135685D01*
G02Y-133291I2252J1197D01*
G01Y-131244D01*
X-1597988D01*
Y-133285D01*
G02Y-135691I-2248J-1203D01*
G01Y-138797D01*
G02Y-141203I-2248J-1203D01*
G37*
G36*
G01X-324681Y-141597D02*
Y-143638D01*
X-329181D01*
Y-141590D01*
G02Y-139197I2252J1197D01*
G01Y-136079D01*
G02Y-133685I2252J1197D01*
G01Y-131638D01*
X-324681D01*
Y-133679D01*
G02Y-136085I-2248J-1203D01*
G01Y-139190D01*
G02Y-141597I-2248J-1203D01*
G37*
G36*
G01X-1194760D02*
Y-143638D01*
X-1199260D01*
Y-141590D01*
G02Y-139197I2252J1197D01*
G01Y-136079D01*
G02Y-133685I2252J1197D01*
G01Y-131638D01*
X-1194760D01*
Y-133679D01*
G02Y-136085I-2248J-1203D01*
G01Y-139190D01*
G02Y-141597I-2248J-1203D01*
G37*
G36*
G01X-110663Y-141594D02*
Y-143638D01*
X-115163D01*
Y-141594D01*
G02Y-139194I2250J1200D01*
G01Y-136082D01*
G02Y-133682I2250J1200D01*
G01Y-131638D01*
X-110663D01*
Y-133682D01*
G02Y-136082I-2250J-1200D01*
G01Y-139194D01*
G02Y-141594I-2250J-1200D01*
G37*
G36*
G01X-126411D02*
Y-143638D01*
X-130911D01*
Y-141594D01*
G02Y-139194I2250J1200D01*
G01Y-136082D01*
G02Y-133682I2250J1200D01*
G01Y-131638D01*
X-126411D01*
Y-133682D01*
G02Y-136082I-2250J-1200D01*
G01Y-139194D01*
G02Y-141594I-2250J-1200D01*
G37*
G36*
G01X-142159D02*
Y-143638D01*
X-146659D01*
Y-141594D01*
G02Y-139194I2250J1200D01*
G01Y-136082D01*
G02Y-133682I2250J1200D01*
G01Y-131638D01*
X-142159D01*
Y-133682D01*
G02Y-136082I-2250J-1200D01*
G01Y-139194D01*
G02Y-141594I-2250J-1200D01*
G37*
G36*
G01X-980742D02*
Y-143638D01*
X-985242D01*
Y-141594D01*
G02Y-139194I2250J1200D01*
G01Y-136082D01*
G02Y-133682I2250J1200D01*
G01Y-131638D01*
X-980742D01*
Y-133682D01*
G02Y-136082I-2250J-1200D01*
G01Y-139194D01*
G02Y-141594I-2250J-1200D01*
G37*
G36*
G01X-996490D02*
Y-143638D01*
X-1000990D01*
Y-141594D01*
G02Y-139194I2250J1200D01*
G01Y-136082D01*
G02Y-133682I2250J1200D01*
G01Y-131638D01*
X-996490D01*
Y-133682D01*
G02Y-136082I-2250J-1200D01*
G01Y-139194D01*
G02Y-141594I-2250J-1200D01*
G37*
G36*
G01X-1012238D02*
Y-143638D01*
X-1016738D01*
Y-141594D01*
G02Y-139194I2250J1200D01*
G01Y-136082D01*
G02Y-133682I2250J1200D01*
G01Y-131638D01*
X-1012238D01*
Y-133682D01*
G02Y-136082I-2250J-1200D01*
G01Y-139194D01*
G02Y-141594I-2250J-1200D01*
G37*
G36*
G01X-391770Y-142354D02*
X-391593Y-142335D01*
X-388300D01*
X-388123Y-142354D01*
G02X-388509Y-146536I-223J-2088D01*
G01X-388518Y-146535D01*
X-391374D01*
X-391384Y-146536D01*
G02X-391770Y-142354I-162J2094D01*
G37*
G36*
G01X-1261849D02*
X-1261672Y-142335D01*
X-1258379D01*
X-1258202Y-142354D01*
G02X-1258587Y-146536I-223J-2088D01*
G01X-1258597Y-146535D01*
X-1261453D01*
X-1261463Y-146536D01*
G02X-1261849Y-142354I-162J2094D01*
G37*
G36*
G01X-672791Y-146321D02*
Y-148362D01*
X-677291D01*
Y-146315D01*
G02Y-143921I2252J1197D01*
G01Y-140803D01*
G02Y-138410I2252J1197D01*
G01Y-136362D01*
X-672791D01*
Y-138403D01*
G02Y-140810I-2248J-1203D01*
G01Y-143915D01*
G02Y-146321I-2248J-1203D01*
G37*
G36*
G01X-688539D02*
Y-148362D01*
X-693039D01*
Y-146315D01*
G02Y-143921I2252J1197D01*
G01Y-140803D01*
G02Y-138410I2252J1197D01*
G01Y-136362D01*
X-688539D01*
Y-138403D01*
G02Y-140810I-2248J-1203D01*
G01Y-143915D01*
G02Y-146321I-2248J-1203D01*
G37*
G36*
G01X-704287D02*
Y-148362D01*
X-708787D01*
Y-146315D01*
G02Y-143921I2252J1197D01*
G01Y-140803D01*
G02Y-138410I2252J1197D01*
G01Y-136362D01*
X-704287D01*
Y-138403D01*
G02Y-140810I-2248J-1203D01*
G01Y-143915D01*
G02Y-146321I-2248J-1203D01*
G37*
G36*
G01X-720035D02*
Y-148362D01*
X-724535D01*
Y-146315D01*
G02Y-143921I2252J1197D01*
G01Y-140803D01*
G02Y-138410I2252J1197D01*
G01Y-136362D01*
X-720035D01*
Y-138403D01*
G02Y-140810I-2248J-1203D01*
G01Y-143915D01*
G02Y-146321I-2248J-1203D01*
G37*
G36*
G01X-735783D02*
Y-148362D01*
X-740283D01*
Y-146315D01*
G02Y-143921I2252J1197D01*
G01Y-140803D01*
G02Y-138410I2252J1197D01*
G01Y-136362D01*
X-735783D01*
Y-138403D01*
G02Y-140810I-2248J-1203D01*
G01Y-143915D01*
G02Y-146321I-2248J-1203D01*
G37*
G36*
G01X-1542870D02*
Y-148362D01*
X-1547370D01*
Y-146315D01*
G02Y-143921I2252J1197D01*
G01Y-140803D01*
G02Y-138410I2252J1197D01*
G01Y-136362D01*
X-1542870D01*
Y-138403D01*
G02Y-140810I-2248J-1203D01*
G01Y-143915D01*
G02Y-146321I-2248J-1203D01*
G37*
G36*
G01X-1558618D02*
Y-148362D01*
X-1563118D01*
Y-146315D01*
G02Y-143921I2252J1197D01*
G01Y-140803D01*
G02Y-138410I2252J1197D01*
G01Y-136362D01*
X-1558618D01*
Y-138403D01*
G02Y-140810I-2248J-1203D01*
G01Y-143915D01*
G02Y-146321I-2248J-1203D01*
G37*
G36*
G01X-1574366D02*
Y-148362D01*
X-1578866D01*
Y-146315D01*
G02Y-143921I2252J1197D01*
G01Y-140803D01*
G02Y-138410I2252J1197D01*
G01Y-136362D01*
X-1574366D01*
Y-138403D01*
G02Y-140810I-2248J-1203D01*
G01Y-143915D01*
G02Y-146321I-2248J-1203D01*
G37*
G36*
G01X-1590114D02*
Y-148362D01*
X-1594614D01*
Y-146315D01*
G02Y-143921I2252J1197D01*
G01Y-140803D01*
G02Y-138410I2252J1197D01*
G01Y-136362D01*
X-1590114D01*
Y-138403D01*
G02Y-140810I-2248J-1203D01*
G01Y-143915D01*
G02Y-146321I-2248J-1203D01*
G37*
G36*
G01X-1605862D02*
Y-148362D01*
X-1610362D01*
Y-146315D01*
G02Y-143921I2252J1197D01*
G01Y-140803D01*
G02Y-138410I2252J1197D01*
G01Y-136362D01*
X-1605862D01*
Y-138403D01*
G02Y-140810I-2248J-1203D01*
G01Y-143915D01*
G02Y-146321I-2248J-1203D01*
G37*
G36*
G01X-593212Y-146800D02*
X-593211Y-146793D01*
Y-141986D01*
X-593212Y-141979D01*
G02X-590029Y-141674I1598J90D01*
G01X-590011Y-141803D01*
Y-146977D01*
X-590029Y-147106D01*
G02X-593212Y-146800I-1585J216D01*
G37*
G36*
G01X-603212D02*
X-603211Y-146793D01*
Y-141986D01*
X-603212Y-141979D01*
G02X-600029Y-141674I1598J90D01*
G01X-600011Y-141803D01*
Y-146977D01*
X-600029Y-147106D01*
G02X-603212Y-146800I-1585J216D01*
G37*
G36*
G01X-613212D02*
X-613211Y-146793D01*
Y-141986D01*
X-613212Y-141979D01*
G02X-610029Y-141674I1598J90D01*
G01X-610011Y-141803D01*
Y-146977D01*
X-610029Y-147106D01*
G02X-613212Y-146800I-1585J216D01*
G37*
G36*
G01X-1463290D02*
X-1463290Y-146793D01*
Y-141986D01*
X-1463290Y-141979D01*
G02X-1460108Y-141674I1598J90D01*
G01X-1460090Y-141803D01*
Y-146977D01*
X-1460108Y-147106D01*
G02X-1463290Y-146800I-1585J216D01*
G37*
G36*
G01X-1473290D02*
X-1473290Y-146793D01*
Y-141986D01*
X-1473290Y-141979D01*
G02X-1470108Y-141674I1598J90D01*
G01X-1470090Y-141803D01*
Y-146977D01*
X-1470108Y-147106D01*
G02X-1473290Y-146800I-1585J216D01*
G37*
G36*
G01X-1483290D02*
X-1483290Y-146793D01*
Y-141986D01*
X-1483290Y-141979D01*
G02X-1480108Y-141674I1598J90D01*
G01X-1480090Y-141803D01*
Y-146977D01*
X-1480108Y-147106D01*
G02X-1483290Y-146800I-1585J216D01*
G37*
G36*
G01X-102789Y-146712D02*
Y-148756D01*
X-107289D01*
Y-146712D01*
G02Y-144312I2250J1200D01*
G01Y-141200D01*
G02Y-138800I2250J1200D01*
G01Y-136756D01*
X-102789D01*
Y-138800D01*
G02Y-141200I-2250J-1200D01*
G01Y-144312D01*
G02Y-146712I-2250J-1200D01*
G37*
G36*
G01X-118537D02*
Y-148756D01*
X-123037D01*
Y-146712D01*
G02Y-144312I2250J1200D01*
G01Y-141200D01*
G02Y-138800I2250J1200D01*
G01Y-136756D01*
X-118537D01*
Y-138800D01*
G02Y-141200I-2250J-1200D01*
G01Y-144312D01*
G02Y-146712I-2250J-1200D01*
G37*
G36*
G01X-134285D02*
Y-148756D01*
X-138785D01*
Y-146712D01*
G02Y-144312I2250J1200D01*
G01Y-141200D01*
G02Y-138800I2250J1200D01*
G01Y-136756D01*
X-134285D01*
Y-138800D01*
G02Y-141200I-2250J-1200D01*
G01Y-144312D01*
G02Y-146712I-2250J-1200D01*
G37*
G36*
G01X-972868D02*
Y-148756D01*
X-977368D01*
Y-146712D01*
G02Y-144312I2250J1200D01*
G01Y-141200D01*
G02Y-138800I2250J1200D01*
G01Y-136756D01*
X-972868D01*
Y-138800D01*
G02Y-141200I-2250J-1200D01*
G01Y-144312D01*
G02Y-146712I-2250J-1200D01*
G37*
G36*
G01X-988616D02*
Y-148756D01*
X-993116D01*
Y-146712D01*
G02Y-144312I2250J1200D01*
G01Y-141200D01*
G02Y-138800I2250J1200D01*
G01Y-136756D01*
X-988616D01*
Y-138800D01*
G02Y-141200I-2250J-1200D01*
G01Y-144312D01*
G02Y-146712I-2250J-1200D01*
G37*
G36*
G01X-1004364D02*
Y-148756D01*
X-1008864D01*
Y-146712D01*
G02Y-144312I2250J1200D01*
G01Y-141200D01*
G02Y-138800I2250J1200D01*
G01Y-136756D01*
X-1004364D01*
Y-138800D01*
G02Y-141200I-2250J-1200D01*
G01Y-144312D01*
G02Y-146712I-2250J-1200D01*
G37*
G36*
G01X-285311Y-146715D02*
Y-148756D01*
X-289811D01*
Y-146709D01*
G02Y-144315I2252J1197D01*
G01Y-141197D01*
G02Y-138803I2252J1197D01*
G01Y-136756D01*
X-285311D01*
Y-138797D01*
G02Y-141203I-2248J-1203D01*
G01Y-144309D01*
G02Y-146715I-2248J-1203D01*
G37*
G36*
G01X-1155390D02*
Y-148756D01*
X-1159890D01*
Y-146709D01*
G02Y-144315I2252J1197D01*
G01Y-141197D01*
G02Y-138803I2252J1197D01*
G01Y-136756D01*
X-1155390D01*
Y-138797D01*
G02Y-141203I-2248J-1203D01*
G01Y-144309D01*
G02Y-146715I-2248J-1203D01*
G37*
G36*
G01X-353935Y-147819D02*
X-353757Y-147800D01*
X-350465D01*
X-350288Y-147819D01*
G02X-350673Y-152001I-223J-2088D01*
G01X-350683Y-152000D01*
X-353539D01*
X-353548Y-152001D01*
G02X-353935Y-147819I-162J2094D01*
G37*
G36*
G01X-1224013D02*
X-1223836Y-147800D01*
X-1220543D01*
X-1220366Y-147819D01*
G02X-1220752Y-152001I-223J-2088D01*
G01X-1220761Y-152000D01*
X-1223618D01*
X-1223627Y-152001D01*
G02X-1224013Y-147819I-162J2094D01*
G37*
G36*
G01X-401233Y-149699D02*
X-401056Y-149680D01*
X-397763D01*
X-397586Y-149699D01*
G02X-397971Y-153881I-223J-2088D01*
G01X-397981Y-153880D01*
X-400837D01*
X-400847Y-153881D01*
G02X-401233Y-149699I-162J2094D01*
G37*
G36*
G01X-1271312D02*
X-1271134Y-149680D01*
X-1267842D01*
X-1267665Y-149699D01*
G02X-1268050Y-153881I-223J-2088D01*
G01X-1268060Y-153880D01*
X-1270916D01*
X-1270925Y-153881D01*
G02X-1271312Y-149699I-162J2094D01*
G37*
G36*
G01X-253595Y-153102D02*
X-253418Y-153083D01*
X-250125D01*
X-249948Y-153102D01*
G02X-250334Y-157284I-223J-2088D01*
G01X-250343Y-157283D01*
X-253199D01*
X-253209Y-157284D01*
G02X-253595Y-153102I-162J2094D01*
G37*
G36*
G01X-1123674D02*
X-1123497Y-153083D01*
X-1120204D01*
X-1120027Y-153102D01*
G02X-1120412Y-157284I-223J-2088D01*
G01X-1120422Y-157283D01*
X-1123278D01*
X-1123288Y-157284D01*
G02X-1123674Y-153102I-162J2094D01*
G37*
G36*
G01X-598212Y-156800D02*
X-598211Y-156793D01*
Y-151986D01*
X-598212Y-151979D01*
G02X-595029Y-151674I1598J90D01*
G01X-595011Y-151803D01*
Y-156977D01*
X-595029Y-157106D01*
G02X-598212Y-156800I-1585J216D01*
G37*
G36*
G01X-608212D02*
X-608211Y-156793D01*
Y-151986D01*
X-608212Y-151979D01*
G02X-605029Y-151674I1598J90D01*
G01X-605011Y-151803D01*
Y-156977D01*
X-605029Y-157106D01*
G02X-608212Y-156800I-1585J216D01*
G37*
G36*
G01X-618212D02*
X-618211Y-156793D01*
Y-151986D01*
X-618212Y-151979D01*
G02X-615029Y-151674I1598J90D01*
G01X-615011Y-151803D01*
Y-156977D01*
X-615029Y-157106D01*
G02X-618212Y-156800I-1585J216D01*
G37*
G36*
G01X-1468290D02*
X-1468290Y-156793D01*
Y-151986D01*
X-1468290Y-151979D01*
G02X-1465108Y-151674I1598J90D01*
G01X-1465090Y-151803D01*
Y-156977D01*
X-1465108Y-157106D01*
G02X-1468290Y-156800I-1585J216D01*
G37*
G36*
G01X-1478290D02*
X-1478290Y-156793D01*
Y-151986D01*
X-1478290Y-151979D01*
G02X-1475108Y-151674I1598J90D01*
G01X-1475090Y-151803D01*
Y-156977D01*
X-1475108Y-157106D01*
G02X-1478290Y-156800I-1585J216D01*
G37*
G36*
G01X-1488290D02*
X-1488290Y-156793D01*
Y-151986D01*
X-1488290Y-151979D01*
G02X-1485108Y-151674I1598J90D01*
G01X-1485090Y-151803D01*
Y-156977D01*
X-1485108Y-157106D01*
G02X-1488290Y-156800I-1585J216D01*
G37*
G36*
G01X-680665Y-157739D02*
Y-159780D01*
X-685165D01*
Y-157732D01*
G02Y-155339I2252J1197D01*
G01Y-152220D01*
G02Y-149827I2252J1197D01*
G01Y-147780D01*
X-680665D01*
Y-149820D01*
G02Y-152227I-2248J-1203D01*
G01Y-155332D01*
G02Y-157739I-2248J-1203D01*
G37*
G36*
G01X-696413D02*
Y-159780D01*
X-700913D01*
Y-157732D01*
G02Y-155339I2252J1197D01*
G01Y-152220D01*
G02Y-149827I2252J1197D01*
G01Y-147780D01*
X-696413D01*
Y-149820D01*
G02Y-152227I-2248J-1203D01*
G01Y-155332D01*
G02Y-157739I-2248J-1203D01*
G37*
G36*
G01X-712161D02*
Y-159780D01*
X-716661D01*
Y-157732D01*
G02Y-155339I2252J1197D01*
G01Y-152220D01*
G02Y-149827I2252J1197D01*
G01Y-147780D01*
X-712161D01*
Y-149820D01*
G02Y-152227I-2248J-1203D01*
G01Y-155332D01*
G02Y-157739I-2248J-1203D01*
G37*
G36*
G01X-727909D02*
Y-159780D01*
X-732409D01*
Y-157732D01*
G02Y-155339I2252J1197D01*
G01Y-152220D01*
G02Y-149827I2252J1197D01*
G01Y-147780D01*
X-727909D01*
Y-149820D01*
G02Y-152227I-2248J-1203D01*
G01Y-155332D01*
G02Y-157739I-2248J-1203D01*
G37*
G36*
G01X-1550744D02*
Y-159780D01*
X-1555244D01*
Y-157732D01*
G02Y-155339I2252J1197D01*
G01Y-152220D01*
G02Y-149827I2252J1197D01*
G01Y-147780D01*
X-1550744D01*
Y-149820D01*
G02Y-152227I-2248J-1203D01*
G01Y-155332D01*
G02Y-157739I-2248J-1203D01*
G37*
G36*
G01X-1566492D02*
Y-159780D01*
X-1570992D01*
Y-157732D01*
G02Y-155339I2252J1197D01*
G01Y-152220D01*
G02Y-149827I2252J1197D01*
G01Y-147780D01*
X-1566492D01*
Y-149820D01*
G02Y-152227I-2248J-1203D01*
G01Y-155332D01*
G02Y-157739I-2248J-1203D01*
G37*
G36*
G01X-1582240D02*
Y-159780D01*
X-1586740D01*
Y-157732D01*
G02Y-155339I2252J1197D01*
G01Y-152220D01*
G02Y-149827I2252J1197D01*
G01Y-147780D01*
X-1582240D01*
Y-149820D01*
G02Y-152227I-2248J-1203D01*
G01Y-155332D01*
G02Y-157739I-2248J-1203D01*
G37*
G36*
G01X-1597988D02*
Y-159780D01*
X-1602488D01*
Y-157732D01*
G02Y-155339I2252J1197D01*
G01Y-152220D01*
G02Y-149827I2252J1197D01*
G01Y-147780D01*
X-1597988D01*
Y-149820D01*
G02Y-152227I-2248J-1203D01*
G01Y-155332D01*
G02Y-157739I-2248J-1203D01*
G37*
G36*
G01X-324681Y-158132D02*
Y-160173D01*
X-329181D01*
Y-158126D01*
G02Y-155732I2252J1197D01*
G01Y-152614D01*
G02Y-150221I2252J1197D01*
G01Y-148173D01*
X-324681D01*
Y-150214D01*
G02Y-152621I-2248J-1203D01*
G01Y-155726D01*
G02Y-158132I-2248J-1203D01*
G37*
G36*
G01X-1194760D02*
Y-160173D01*
X-1199260D01*
Y-158126D01*
G02Y-155732I2252J1197D01*
G01Y-152614D01*
G02Y-150221I2252J1197D01*
G01Y-148173D01*
X-1194760D01*
Y-150214D01*
G02Y-152621I-2248J-1203D01*
G01Y-155726D01*
G02Y-158132I-2248J-1203D01*
G37*
G36*
G01X-110663Y-158129D02*
Y-160173D01*
X-115163D01*
Y-158129D01*
G02Y-155729I2250J1200D01*
G01Y-152617D01*
G02Y-150217I2250J1200D01*
G01Y-148173D01*
X-110663D01*
Y-150217D01*
G02Y-152617I-2250J-1200D01*
G01Y-155729D01*
G02Y-158129I-2250J-1200D01*
G37*
G36*
G01X-126411D02*
Y-160173D01*
X-130911D01*
Y-158129D01*
G02Y-155729I2250J1200D01*
G01Y-152617D01*
G02Y-150217I2250J1200D01*
G01Y-148173D01*
X-126411D01*
Y-150217D01*
G02Y-152617I-2250J-1200D01*
G01Y-155729D01*
G02Y-158129I-2250J-1200D01*
G37*
G36*
G01X-142159D02*
Y-160173D01*
X-146659D01*
Y-158129D01*
G02Y-155729I2250J1200D01*
G01Y-152617D01*
G02Y-150217I2250J1200D01*
G01Y-148173D01*
X-142159D01*
Y-150217D01*
G02Y-152617I-2250J-1200D01*
G01Y-155729D01*
G02Y-158129I-2250J-1200D01*
G37*
G36*
G01X-980742D02*
Y-160173D01*
X-985242D01*
Y-158129D01*
G02Y-155729I2250J1200D01*
G01Y-152617D01*
G02Y-150217I2250J1200D01*
G01Y-148173D01*
X-980742D01*
Y-150217D01*
G02Y-152617I-2250J-1200D01*
G01Y-155729D01*
G02Y-158129I-2250J-1200D01*
G37*
G36*
G01X-996490D02*
Y-160173D01*
X-1000990D01*
Y-158129D01*
G02Y-155729I2250J1200D01*
G01Y-152617D01*
G02Y-150217I2250J1200D01*
G01Y-148173D01*
X-996490D01*
Y-150217D01*
G02Y-152617I-2250J-1200D01*
G01Y-155729D01*
G02Y-158129I-2250J-1200D01*
G37*
G36*
G01X-1012238D02*
Y-160173D01*
X-1016738D01*
Y-158129D01*
G02Y-155729I2250J1200D01*
G01Y-152617D01*
G02Y-150217I2250J1200D01*
G01Y-148173D01*
X-1012238D01*
Y-150217D01*
G02Y-152617I-2250J-1200D01*
G01Y-155729D01*
G02Y-158129I-2250J-1200D01*
G37*
G36*
G01X-672791Y-162857D02*
Y-164898D01*
X-677291D01*
Y-162850D01*
G02Y-160457I2252J1197D01*
G01Y-157339D01*
G02Y-154945I2252J1197D01*
G01Y-152898D01*
X-672791D01*
Y-154939D01*
G02Y-157345I-2248J-1203D01*
G01Y-160450D01*
G02Y-162857I-2248J-1203D01*
G37*
G36*
G01X-688539D02*
Y-164898D01*
X-693039D01*
Y-162850D01*
G02Y-160457I2252J1197D01*
G01Y-157339D01*
G02Y-154945I2252J1197D01*
G01Y-152898D01*
X-688539D01*
Y-154939D01*
G02Y-157345I-2248J-1203D01*
G01Y-160450D01*
G02Y-162857I-2248J-1203D01*
G37*
G36*
G01X-704287D02*
Y-164898D01*
X-708787D01*
Y-162850D01*
G02Y-160457I2252J1197D01*
G01Y-157339D01*
G02Y-154945I2252J1197D01*
G01Y-152898D01*
X-704287D01*
Y-154939D01*
G02Y-157345I-2248J-1203D01*
G01Y-160450D01*
G02Y-162857I-2248J-1203D01*
G37*
G36*
G01X-720035D02*
Y-164898D01*
X-724535D01*
Y-162850D01*
G02Y-160457I2252J1197D01*
G01Y-157339D01*
G02Y-154945I2252J1197D01*
G01Y-152898D01*
X-720035D01*
Y-154939D01*
G02Y-157345I-2248J-1203D01*
G01Y-160450D01*
G02Y-162857I-2248J-1203D01*
G37*
G36*
G01X-735783D02*
Y-164898D01*
X-740283D01*
Y-162850D01*
G02Y-160457I2252J1197D01*
G01Y-157339D01*
G02Y-154945I2252J1197D01*
G01Y-152898D01*
X-735783D01*
Y-154939D01*
G02Y-157345I-2248J-1203D01*
G01Y-160450D01*
G02Y-162857I-2248J-1203D01*
G37*
G36*
G01X-1542870D02*
Y-164898D01*
X-1547370D01*
Y-162850D01*
G02Y-160457I2252J1197D01*
G01Y-157339D01*
G02Y-154945I2252J1197D01*
G01Y-152898D01*
X-1542870D01*
Y-154939D01*
G02Y-157345I-2248J-1203D01*
G01Y-160450D01*
G02Y-162857I-2248J-1203D01*
G37*
G36*
G01X-1558618D02*
Y-164898D01*
X-1563118D01*
Y-162850D01*
G02Y-160457I2252J1197D01*
G01Y-157339D01*
G02Y-154945I2252J1197D01*
G01Y-152898D01*
X-1558618D01*
Y-154939D01*
G02Y-157345I-2248J-1203D01*
G01Y-160450D01*
G02Y-162857I-2248J-1203D01*
G37*
G36*
G01X-1574366D02*
Y-164898D01*
X-1578866D01*
Y-162850D01*
G02Y-160457I2252J1197D01*
G01Y-157339D01*
G02Y-154945I2252J1197D01*
G01Y-152898D01*
X-1574366D01*
Y-154939D01*
G02Y-157345I-2248J-1203D01*
G01Y-160450D01*
G02Y-162857I-2248J-1203D01*
G37*
G36*
G01X-1590114D02*
Y-164898D01*
X-1594614D01*
Y-162850D01*
G02Y-160457I2252J1197D01*
G01Y-157339D01*
G02Y-154945I2252J1197D01*
G01Y-152898D01*
X-1590114D01*
Y-154939D01*
G02Y-157345I-2248J-1203D01*
G01Y-160450D01*
G02Y-162857I-2248J-1203D01*
G37*
G36*
G01X-1605862D02*
Y-164898D01*
X-1610362D01*
Y-162850D01*
G02Y-160457I2252J1197D01*
G01Y-157339D01*
G02Y-154945I2252J1197D01*
G01Y-152898D01*
X-1605862D01*
Y-154939D01*
G02Y-157345I-2248J-1203D01*
G01Y-160450D01*
G02Y-162857I-2248J-1203D01*
G37*
G36*
G01X-102789Y-163247D02*
Y-165291D01*
X-107289D01*
Y-163247D01*
G02Y-160847I2250J1200D01*
G01Y-157735D01*
G02Y-155335I2250J1200D01*
G01Y-153291D01*
X-102789D01*
Y-155335D01*
G02Y-157735I-2250J-1200D01*
G01Y-160847D01*
G02Y-163247I-2250J-1200D01*
G37*
G36*
G01X-118537D02*
Y-165291D01*
X-123037D01*
Y-163247D01*
G02Y-160847I2250J1200D01*
G01Y-157735D01*
G02Y-155335I2250J1200D01*
G01Y-153291D01*
X-118537D01*
Y-155335D01*
G02Y-157735I-2250J-1200D01*
G01Y-160847D01*
G02Y-163247I-2250J-1200D01*
G37*
G36*
G01X-134285D02*
Y-165291D01*
X-138785D01*
Y-163247D01*
G02Y-160847I2250J1200D01*
G01Y-157735D01*
G02Y-155335I2250J1200D01*
G01Y-153291D01*
X-134285D01*
Y-155335D01*
G02Y-157735I-2250J-1200D01*
G01Y-160847D01*
G02Y-163247I-2250J-1200D01*
G37*
G36*
G01X-972868D02*
Y-165291D01*
X-977368D01*
Y-163247D01*
G02Y-160847I2250J1200D01*
G01Y-157735D01*
G02Y-155335I2250J1200D01*
G01Y-153291D01*
X-972868D01*
Y-155335D01*
G02Y-157735I-2250J-1200D01*
G01Y-160847D01*
G02Y-163247I-2250J-1200D01*
G37*
G36*
G01X-988616D02*
Y-165291D01*
X-993116D01*
Y-163247D01*
G02Y-160847I2250J1200D01*
G01Y-157735D01*
G02Y-155335I2250J1200D01*
G01Y-153291D01*
X-988616D01*
Y-155335D01*
G02Y-157735I-2250J-1200D01*
G01Y-160847D01*
G02Y-163247I-2250J-1200D01*
G37*
G36*
G01X-1004364D02*
Y-165291D01*
X-1008864D01*
Y-163247D01*
G02Y-160847I2250J1200D01*
G01Y-157735D01*
G02Y-155335I2250J1200D01*
G01Y-153291D01*
X-1004364D01*
Y-155335D01*
G02Y-157735I-2250J-1200D01*
G01Y-160847D01*
G02Y-163247I-2250J-1200D01*
G37*
G36*
G01X-285311Y-163250D02*
Y-165291D01*
X-289811D01*
Y-163244D01*
G02Y-160850I2252J1197D01*
G01Y-157732D01*
G02Y-155339I2252J1197D01*
G01Y-153291D01*
X-285311D01*
Y-155332D01*
G02Y-157739I-2248J-1203D01*
G01Y-160844D01*
G02Y-163250I-2248J-1203D01*
G37*
G36*
G01X-1155390D02*
Y-165291D01*
X-1159890D01*
Y-163244D01*
G02Y-160850I2252J1197D01*
G01Y-157732D01*
G02Y-155339I2252J1197D01*
G01Y-153291D01*
X-1155390D01*
Y-155332D01*
G02Y-157739I-2248J-1203D01*
G01Y-160844D01*
G02Y-163250I-2248J-1203D01*
G37*
G36*
G01X-593212Y-166800D02*
X-593211Y-166793D01*
Y-161986D01*
X-593212Y-161979D01*
G02X-590029Y-161674I1598J90D01*
G01X-590011Y-161803D01*
Y-166977D01*
X-590029Y-167106D01*
G02X-593212Y-166800I-1585J216D01*
G37*
G36*
G01X-603212D02*
X-603211Y-166793D01*
Y-161986D01*
X-603212Y-161979D01*
G02X-600029Y-161674I1598J90D01*
G01X-600011Y-161803D01*
Y-166977D01*
X-600029Y-167106D01*
G02X-603212Y-166800I-1585J216D01*
G37*
G36*
G01X-613212D02*
X-613211Y-166793D01*
Y-161986D01*
X-613212Y-161979D01*
G02X-610029Y-161674I1598J90D01*
G01X-610011Y-161803D01*
Y-166977D01*
X-610029Y-167106D01*
G02X-613212Y-166800I-1585J216D01*
G37*
G36*
G01X-1463290D02*
X-1463290Y-166793D01*
Y-161986D01*
X-1463290Y-161979D01*
G02X-1460108Y-161674I1598J90D01*
G01X-1460090Y-161803D01*
Y-166977D01*
X-1460108Y-167106D01*
G02X-1463290Y-166800I-1585J216D01*
G37*
G36*
G01X-1473290D02*
X-1473290Y-166793D01*
Y-161986D01*
X-1473290Y-161979D01*
G02X-1470108Y-161674I1598J90D01*
G01X-1470090Y-161803D01*
Y-166977D01*
X-1470108Y-167106D01*
G02X-1473290Y-166800I-1585J216D01*
G37*
G36*
G01X-1483290D02*
X-1483290Y-166793D01*
Y-161986D01*
X-1483290Y-161979D01*
G02X-1480108Y-161674I1598J90D01*
G01X-1480090Y-161803D01*
Y-166977D01*
X-1480108Y-167106D01*
G02X-1483290Y-166800I-1585J216D01*
G37*
G36*
G01X-339565Y-165279D02*
X-339387Y-165260D01*
X-336095D01*
X-335918Y-165279D01*
G02X-336303Y-169461I-223J-2088D01*
G01X-336313Y-169460D01*
X-339169D01*
X-339179Y-169461D01*
G02X-339565Y-165279I-162J2094D01*
G37*
G36*
G01X-1209643D02*
X-1209466Y-165260D01*
X-1206174D01*
X-1205997Y-165279D01*
G02X-1206382Y-169461I-223J-2088D01*
G01X-1206392Y-169460D01*
X-1209248D01*
X-1209257Y-169461D01*
G02X-1209643Y-165279I-162J2094D01*
G37*
G36*
G01X-680665Y-174274D02*
Y-176315D01*
X-685165D01*
Y-174268D01*
G02Y-171874I2252J1197D01*
G01Y-168756D01*
G02Y-166362I2252J1197D01*
G01Y-164315D01*
X-680665D01*
Y-166356D01*
G02Y-168762I-2248J-1203D01*
G01Y-171868D01*
G02Y-174274I-2248J-1203D01*
G37*
G36*
G01X-696413D02*
Y-176315D01*
X-700913D01*
Y-174268D01*
G02Y-171874I2252J1197D01*
G01Y-168756D01*
G02Y-166362I2252J1197D01*
G01Y-164315D01*
X-696413D01*
Y-166356D01*
G02Y-168762I-2248J-1203D01*
G01Y-171868D01*
G02Y-174274I-2248J-1203D01*
G37*
G36*
G01X-712161D02*
Y-176315D01*
X-716661D01*
Y-174268D01*
G02Y-171874I2252J1197D01*
G01Y-168756D01*
G02Y-166362I2252J1197D01*
G01Y-164315D01*
X-712161D01*
Y-166356D01*
G02Y-168762I-2248J-1203D01*
G01Y-171868D01*
G02Y-174274I-2248J-1203D01*
G37*
G36*
G01X-727909D02*
Y-176315D01*
X-732409D01*
Y-174268D01*
G02Y-171874I2252J1197D01*
G01Y-168756D01*
G02Y-166362I2252J1197D01*
G01Y-164315D01*
X-727909D01*
Y-166356D01*
G02Y-168762I-2248J-1203D01*
G01Y-171868D01*
G02Y-174274I-2248J-1203D01*
G37*
G36*
G01X-743657D02*
Y-176315D01*
X-748157D01*
Y-174268D01*
G02Y-171874I2252J1197D01*
G01Y-168756D01*
G02Y-166362I2252J1197D01*
G01Y-164315D01*
X-743657D01*
Y-166356D01*
G02Y-168762I-2248J-1203D01*
G01Y-171868D01*
G02Y-174274I-2248J-1203D01*
G37*
G36*
G01X-1550744D02*
Y-176315D01*
X-1555244D01*
Y-174268D01*
G02Y-171874I2252J1197D01*
G01Y-168756D01*
G02Y-166362I2252J1197D01*
G01Y-164315D01*
X-1550744D01*
Y-166356D01*
G02Y-168762I-2248J-1203D01*
G01Y-171868D01*
G02Y-174274I-2248J-1203D01*
G37*
G36*
G01X-1566492D02*
Y-176315D01*
X-1570992D01*
Y-174268D01*
G02Y-171874I2252J1197D01*
G01Y-168756D01*
G02Y-166362I2252J1197D01*
G01Y-164315D01*
X-1566492D01*
Y-166356D01*
G02Y-168762I-2248J-1203D01*
G01Y-171868D01*
G02Y-174274I-2248J-1203D01*
G37*
G36*
G01X-1582240D02*
Y-176315D01*
X-1586740D01*
Y-174268D01*
G02Y-171874I2252J1197D01*
G01Y-168756D01*
G02Y-166362I2252J1197D01*
G01Y-164315D01*
X-1582240D01*
Y-166356D01*
G02Y-168762I-2248J-1203D01*
G01Y-171868D01*
G02Y-174274I-2248J-1203D01*
G37*
G36*
G01X-1597988D02*
Y-176315D01*
X-1602488D01*
Y-174268D01*
G02Y-171874I2252J1197D01*
G01Y-168756D01*
G02Y-166362I2252J1197D01*
G01Y-164315D01*
X-1597988D01*
Y-166356D01*
G02Y-168762I-2248J-1203D01*
G01Y-171868D01*
G02Y-174274I-2248J-1203D01*
G37*
G36*
G01X-1613736D02*
Y-176315D01*
X-1618236D01*
Y-174268D01*
G02Y-171874I2252J1197D01*
G01Y-168756D01*
G02Y-166362I2252J1197D01*
G01Y-164315D01*
X-1613736D01*
Y-166356D01*
G02Y-168762I-2248J-1203D01*
G01Y-171868D01*
G02Y-174274I-2248J-1203D01*
G37*
G36*
G01X-1347998Y-164437D02*
G02Y-169894I-8891J-2729D01*
G02Y-164437I-8891J2729D01*
G37*
G36*
G01X-110663Y-174665D02*
Y-176709D01*
X-115163D01*
Y-174665D01*
G02Y-172265I2250J1200D01*
G01Y-169153D01*
G02Y-166753I2250J1200D01*
G01Y-164709D01*
X-110663D01*
Y-166753D01*
G02Y-169153I-2250J-1200D01*
G01Y-172265D01*
G02Y-174665I-2250J-1200D01*
G37*
G36*
G01X-142159D02*
Y-176709D01*
X-146659D01*
Y-174665D01*
G02Y-172265I2250J1200D01*
G01Y-169153D01*
G02Y-166753I2250J1200D01*
G01Y-164709D01*
X-142159D01*
Y-166753D01*
G02Y-169153I-2250J-1200D01*
G01Y-172265D01*
G02Y-174665I-2250J-1200D01*
G37*
G36*
G01X-980742D02*
Y-176709D01*
X-985242D01*
Y-174665D01*
G02Y-172265I2250J1200D01*
G01Y-169153D01*
G02Y-166753I2250J1200D01*
G01Y-164709D01*
X-980742D01*
Y-166753D01*
G02Y-169153I-2250J-1200D01*
G01Y-172265D01*
G02Y-174665I-2250J-1200D01*
G37*
G36*
G01X-1012238D02*
Y-176709D01*
X-1016738D01*
Y-174665D01*
G02Y-172265I2250J1200D01*
G01Y-169153D01*
G02Y-166753I2250J1200D01*
G01Y-164709D01*
X-1012238D01*
Y-166753D01*
G02Y-169153I-2250J-1200D01*
G01Y-172265D01*
G02Y-174665I-2250J-1200D01*
G37*
G36*
G01X-293185Y-174668D02*
Y-176709D01*
X-297685D01*
Y-174661D01*
G02Y-172268I2252J1197D01*
G01Y-169150D01*
G02Y-166756I2252J1197D01*
G01Y-164709D01*
X-293185D01*
Y-166750D01*
G02Y-169156I-2248J-1203D01*
G01Y-172261D01*
G02Y-174668I-2248J-1203D01*
G37*
G36*
G01X-308933D02*
Y-176709D01*
X-313433D01*
Y-174661D01*
G02Y-172268I2252J1197D01*
G01Y-169150D01*
G02Y-166756I2252J1197D01*
G01Y-164709D01*
X-308933D01*
Y-166750D01*
G02Y-169156I-2248J-1203D01*
G01Y-172261D01*
G02Y-174668I-2248J-1203D01*
G37*
G36*
G01X-324681D02*
Y-176709D01*
X-329181D01*
Y-174661D01*
G02Y-172268I2252J1197D01*
G01Y-169150D01*
G02Y-166756I2252J1197D01*
G01Y-164709D01*
X-324681D01*
Y-166750D01*
G02Y-169156I-2248J-1203D01*
G01Y-172261D01*
G02Y-174668I-2248J-1203D01*
G37*
G36*
G01X-1163264D02*
Y-176709D01*
X-1167764D01*
Y-174661D01*
G02Y-172268I2252J1197D01*
G01Y-169150D01*
G02Y-166756I2252J1197D01*
G01Y-164709D01*
X-1163264D01*
Y-166750D01*
G02Y-169156I-2248J-1203D01*
G01Y-172261D01*
G02Y-174668I-2248J-1203D01*
G37*
G36*
G01X-1179012D02*
Y-176709D01*
X-1183512D01*
Y-174661D01*
G02Y-172268I2252J1197D01*
G01Y-169150D01*
G02Y-166756I2252J1197D01*
G01Y-164709D01*
X-1179012D01*
Y-166750D01*
G02Y-169156I-2248J-1203D01*
G01Y-172261D01*
G02Y-174668I-2248J-1203D01*
G37*
G36*
G01X-1194760D02*
Y-176709D01*
X-1199260D01*
Y-174661D01*
G02Y-172268I2252J1197D01*
G01Y-169150D01*
G02Y-166756I2252J1197D01*
G01Y-164709D01*
X-1194760D01*
Y-166750D01*
G02Y-169156I-2248J-1203D01*
G01Y-172261D01*
G02Y-174668I-2248J-1203D01*
G37*
G36*
G01X-1224946Y-167860D02*
X-1225946Y-166860D01*
Y-158660D01*
X-1224946Y-157660D01*
X-1219546D01*
X-1218546Y-158660D01*
Y-166860D01*
X-1218762Y-167076D01*
G03X-1218585Y-167502I177J-177D01*
G01X-1217971D01*
X-1216971Y-168503D01*
Y-176703D01*
X-1217971Y-177703D01*
X-1223371D01*
X-1224371Y-176703D01*
Y-168503D01*
X-1224155Y-168287D01*
G03X-1224332Y-167860I-177J177D01*
G01X-1224946D01*
G37*
G36*
G01X-1234395D02*
X-1235395Y-166860D01*
Y-158660D01*
X-1234395Y-157660D01*
X-1228995D01*
X-1227995Y-158660D01*
Y-166860D01*
X-1228210Y-167076D01*
G03X-1228034Y-167502I177J-177D01*
G01X-1227420D01*
X-1226420Y-168503D01*
Y-176703D01*
X-1227420Y-177703D01*
X-1232820D01*
X-1233820Y-176703D01*
Y-168503D01*
X-1233604Y-168287D01*
G03X-1233781Y-167860I-177J177D01*
G01X-1234395D01*
G37*
G36*
G01X-1262741D02*
X-1263741Y-166860D01*
Y-158660D01*
X-1262741Y-157660D01*
X-1257341D01*
X-1256341Y-158660D01*
Y-166860D01*
X-1256557Y-167076D01*
G03X-1256380Y-167502I177J-177D01*
G01X-1255766D01*
X-1254766Y-168503D01*
Y-176703D01*
X-1255766Y-177703D01*
X-1261166D01*
X-1262166Y-176703D01*
Y-168503D01*
X-1261951Y-168287D01*
G03X-1262127Y-167860I-177J177D01*
G01X-1262741D01*
G37*
G36*
G01X-1272190D02*
X-1273190Y-166860D01*
Y-158660D01*
X-1272190Y-157660D01*
X-1266790D01*
X-1265790Y-158660D01*
Y-166860D01*
X-1266006Y-167076D01*
G03X-1265829Y-167502I177J-177D01*
G01X-1265215D01*
X-1264215Y-168503D01*
Y-176703D01*
X-1265215Y-177703D01*
X-1270615D01*
X-1271615Y-176703D01*
Y-168503D01*
X-1271400Y-168287D01*
G03X-1271576Y-167860I-177J177D01*
G01X-1272190D01*
G37*
G36*
G01X-353288Y-178086D02*
X-354288Y-177086D01*
Y-168244D01*
X-354863D01*
X-355863Y-167244D01*
Y-158244D01*
X-354863Y-157244D01*
X-349463D01*
X-348463Y-158244D01*
Y-167086D01*
X-347888D01*
X-346888Y-168086D01*
Y-177086D01*
X-347888Y-178086D01*
X-353288D01*
G37*
G36*
G01X-362737D02*
X-363737Y-177086D01*
Y-168244D01*
X-364311D01*
X-365311Y-167244D01*
Y-158244D01*
X-364311Y-157244D01*
X-358911D01*
X-357911Y-158244D01*
Y-167086D01*
X-357337D01*
X-356337Y-168086D01*
Y-177086D01*
X-357337Y-178086D01*
X-362737D01*
G37*
G36*
G01X-391083D02*
X-392083Y-177086D01*
Y-168244D01*
X-392658D01*
X-393658Y-167244D01*
Y-158244D01*
X-392658Y-157244D01*
X-387258D01*
X-386258Y-158244D01*
Y-167086D01*
X-385683D01*
X-384683Y-168086D01*
Y-177086D01*
X-385683Y-178086D01*
X-391083D01*
G37*
G36*
G01X-396707Y-157244D02*
X-395707Y-158244D01*
Y-167086D01*
X-395132D01*
X-394132Y-168086D01*
Y-177086D01*
X-395132Y-178086D01*
X-400532D01*
X-401532Y-177086D01*
Y-168244D01*
X-402107D01*
X-403107Y-167244D01*
Y-158244D01*
X-402107Y-157244D01*
X-396707D01*
G37*
G36*
G01X-672791Y-179392D02*
Y-181433D01*
X-677291D01*
Y-179386D01*
G02Y-176992I2252J1197D01*
G01Y-173874D01*
G02Y-171480I2252J1197D01*
G01Y-169433D01*
X-672791D01*
Y-171474D01*
G02Y-173880I-2248J-1203D01*
G01Y-176986D01*
G02Y-179392I-2248J-1203D01*
G37*
G36*
G01X-688539D02*
Y-181433D01*
X-693039D01*
Y-179386D01*
G02Y-176992I2252J1197D01*
G01Y-173874D01*
G02Y-171480I2252J1197D01*
G01Y-169433D01*
X-688539D01*
Y-171474D01*
G02Y-173880I-2248J-1203D01*
G01Y-176986D01*
G02Y-179392I-2248J-1203D01*
G37*
G36*
G01X-704287D02*
Y-181433D01*
X-708787D01*
Y-179386D01*
G02Y-176992I2252J1197D01*
G01Y-173874D01*
G02Y-171480I2252J1197D01*
G01Y-169433D01*
X-704287D01*
Y-171474D01*
G02Y-173880I-2248J-1203D01*
G01Y-176986D01*
G02Y-179392I-2248J-1203D01*
G37*
G36*
G01X-720035D02*
Y-181433D01*
X-724535D01*
Y-179386D01*
G02Y-176992I2252J1197D01*
G01Y-173874D01*
G02Y-171480I2252J1197D01*
G01Y-169433D01*
X-720035D01*
Y-171474D01*
G02Y-173880I-2248J-1203D01*
G01Y-176986D01*
G02Y-179392I-2248J-1203D01*
G37*
G36*
G01X-735783D02*
Y-181433D01*
X-740283D01*
Y-179386D01*
G02Y-176992I2252J1197D01*
G01Y-173874D01*
G02Y-171480I2252J1197D01*
G01Y-169433D01*
X-735783D01*
Y-171474D01*
G02Y-173880I-2248J-1203D01*
G01Y-176986D01*
G02Y-179392I-2248J-1203D01*
G37*
G36*
G01X-1542870D02*
Y-181433D01*
X-1547370D01*
Y-179386D01*
G02Y-176992I2252J1197D01*
G01Y-173874D01*
G02Y-171480I2252J1197D01*
G01Y-169433D01*
X-1542870D01*
Y-171474D01*
G02Y-173880I-2248J-1203D01*
G01Y-176986D01*
G02Y-179392I-2248J-1203D01*
G37*
G36*
G01X-1558618D02*
Y-181433D01*
X-1563118D01*
Y-179386D01*
G02Y-176992I2252J1197D01*
G01Y-173874D01*
G02Y-171480I2252J1197D01*
G01Y-169433D01*
X-1558618D01*
Y-171474D01*
G02Y-173880I-2248J-1203D01*
G01Y-176986D01*
G02Y-179392I-2248J-1203D01*
G37*
G36*
G01X-1574366D02*
Y-181433D01*
X-1578866D01*
Y-179386D01*
G02Y-176992I2252J1197D01*
G01Y-173874D01*
G02Y-171480I2252J1197D01*
G01Y-169433D01*
X-1574366D01*
Y-171474D01*
G02Y-173880I-2248J-1203D01*
G01Y-176986D01*
G02Y-179392I-2248J-1203D01*
G37*
G36*
G01X-1590114D02*
Y-181433D01*
X-1594614D01*
Y-179386D01*
G02Y-176992I2252J1197D01*
G01Y-173874D01*
G02Y-171480I2252J1197D01*
G01Y-169433D01*
X-1590114D01*
Y-171474D01*
G02Y-173880I-2248J-1203D01*
G01Y-176986D01*
G02Y-179392I-2248J-1203D01*
G37*
G36*
G01X-1605862D02*
Y-181433D01*
X-1610362D01*
Y-179386D01*
G02Y-176992I2252J1197D01*
G01Y-173874D01*
G02Y-171480I2252J1197D01*
G01Y-169433D01*
X-1605862D01*
Y-171474D01*
G02Y-173880I-2248J-1203D01*
G01Y-176986D01*
G02Y-179392I-2248J-1203D01*
G37*
G36*
G01X-102789Y-179783D02*
Y-181827D01*
X-107289D01*
Y-179783D01*
G02Y-177383I2250J1200D01*
G01Y-174271D01*
G02Y-171871I2250J1200D01*
G01Y-169827D01*
X-102789D01*
Y-171871D01*
G02Y-174271I-2250J-1200D01*
G01Y-177383D01*
G02Y-179783I-2250J-1200D01*
G37*
G36*
G01X-134285D02*
Y-181827D01*
X-138785D01*
Y-179783D01*
G02Y-177383I2250J1200D01*
G01Y-174271D01*
G02Y-171871I2250J1200D01*
G01Y-169827D01*
X-134285D01*
Y-171871D01*
G02Y-174271I-2250J-1200D01*
G01Y-177383D01*
G02Y-179783I-2250J-1200D01*
G37*
G36*
G01X-972868D02*
Y-181827D01*
X-977368D01*
Y-179783D01*
G02Y-177383I2250J1200D01*
G01Y-174271D01*
G02Y-171871I2250J1200D01*
G01Y-169827D01*
X-972868D01*
Y-171871D01*
G02Y-174271I-2250J-1200D01*
G01Y-177383D01*
G02Y-179783I-2250J-1200D01*
G37*
G36*
G01X-1004364D02*
Y-181827D01*
X-1008864D01*
Y-179783D01*
G02Y-177383I2250J1200D01*
G01Y-174271D01*
G02Y-171871I2250J1200D01*
G01Y-169827D01*
X-1004364D01*
Y-171871D01*
G02Y-174271I-2250J-1200D01*
G01Y-177383D01*
G02Y-179783I-2250J-1200D01*
G37*
G36*
G01X-285311Y-179786D02*
Y-181827D01*
X-289811D01*
Y-179779D01*
G02Y-177386I2252J1197D01*
G01Y-174268D01*
G02Y-171874I2252J1197D01*
G01Y-169827D01*
X-285311D01*
Y-171868D01*
G02Y-174274I-2248J-1203D01*
G01Y-177379D01*
G02Y-179786I-2248J-1203D01*
G37*
G36*
G01X-301059D02*
Y-181827D01*
X-305559D01*
Y-179779D01*
G02Y-177386I2252J1197D01*
G01Y-174268D01*
G02Y-171874I2252J1197D01*
G01Y-169827D01*
X-301059D01*
Y-171868D01*
G02Y-174274I-2248J-1203D01*
G01Y-177379D01*
G02Y-179786I-2248J-1203D01*
G37*
G36*
G01X-316807D02*
Y-181827D01*
X-321307D01*
Y-179779D01*
G02Y-177386I2252J1197D01*
G01Y-174268D01*
G02Y-171874I2252J1197D01*
G01Y-169827D01*
X-316807D01*
Y-171868D01*
G02Y-174274I-2248J-1203D01*
G01Y-177379D01*
G02Y-179786I-2248J-1203D01*
G37*
G36*
G01X-1155390D02*
Y-181827D01*
X-1159890D01*
Y-179779D01*
G02Y-177386I2252J1197D01*
G01Y-174268D01*
G02Y-171874I2252J1197D01*
G01Y-169827D01*
X-1155390D01*
Y-171868D01*
G02Y-174274I-2248J-1203D01*
G01Y-177379D01*
G02Y-179786I-2248J-1203D01*
G37*
G36*
G01X-1171138D02*
Y-181827D01*
X-1175638D01*
Y-179779D01*
G02Y-177386I2252J1197D01*
G01Y-174268D01*
G02Y-171874I2252J1197D01*
G01Y-169827D01*
X-1171138D01*
Y-171868D01*
G02Y-174274I-2248J-1203D01*
G01Y-177379D01*
G02Y-179786I-2248J-1203D01*
G37*
G36*
G01X-1186886D02*
Y-181827D01*
X-1191386D01*
Y-179779D01*
G02Y-177386I2252J1197D01*
G01Y-174268D01*
G02Y-171874I2252J1197D01*
G01Y-169827D01*
X-1186886D01*
Y-171868D01*
G02Y-174274I-2248J-1203D01*
G01Y-177379D01*
G02Y-179786I-2248J-1203D01*
G37*
G36*
G01X-399658Y-181556D02*
X-399481Y-181537D01*
X-396188D01*
X-396011Y-181556D01*
G02X-396397Y-185738I-223J-2088D01*
G01X-396406Y-185737D01*
X-399262D01*
X-399272Y-185738D01*
G02X-399658Y-181556I-162J2094D01*
G37*
G36*
G01X-1269737D02*
X-1269560Y-181537D01*
X-1266267D01*
X-1266090Y-181556D01*
G02X-1266475Y-185738I-223J-2088D01*
G01X-1266485Y-185737D01*
X-1269341D01*
X-1269351Y-185738D01*
G02X-1269737Y-181556I-162J2094D01*
G37*
G36*
G01X-365685Y-183299D02*
X-365507Y-183280D01*
X-362215D01*
X-362038Y-183299D01*
G02X-362423Y-187481I-223J-2088D01*
G01X-362433Y-187480D01*
X-365289D01*
X-365299Y-187481D01*
G02X-365685Y-183299I-162J2094D01*
G37*
G36*
G01X-1235763D02*
X-1235586Y-183280D01*
X-1232294D01*
X-1232117Y-183299D01*
G02X-1232502Y-187481I-223J-2088D01*
G01X-1232512Y-187480D01*
X-1235368D01*
X-1235377Y-187481D01*
G02X-1235763Y-183299I-162J2094D01*
G37*
G36*
G01X-377732Y-190129D02*
X-377751Y-189952D01*
Y-186659D01*
X-377732Y-186482D01*
G02X-373550Y-186868I2088J-223D01*
G01X-373551Y-186877D01*
Y-189733D01*
X-373550Y-189743D01*
G02X-377732Y-190129I-2094J-162D01*
G37*
G36*
G01X-1247811D02*
X-1247830Y-189952D01*
Y-186659D01*
X-1247811Y-186482D01*
G02X-1243629Y-186868I2088J-223D01*
G01X-1243630Y-186877D01*
Y-189733D01*
X-1243629Y-189743D01*
G02X-1247811Y-190129I-2094J-162D01*
G37*
G36*
G01X-1450413Y-73798D02*
G02X-1451378Y-72526I-1587J-202D01*
G03X-1450687Y-72002I194J461D01*
G02X-1450693Y-71655I1587J202D01*
G03X-1451336Y-71131I-498J45D01*
G02X-1451114Y-68154I-464J1531D01*
G03X-1450400Y-67702I214J452D01*
G02X-1450399Y-67655I1600J2D01*
G03X-1451090Y-67179I-500J14D01*
G02X-1451090Y-64221I-610J1479D01*
G03X-1450400Y-63768I191J462D01*
G02X-1450366Y-63473I1600J-32D01*
G03X-1450731Y-63203I-245J51D01*
G02X-1450966Y-60292I-769J1403D01*
G03X-1450299Y-59840I167J471D01*
G02X-1449234Y-61408I1599J-60D01*
G03X-1449901Y-61860I-167J-471D01*
G02X-1449934Y-62127I-1599J61D01*
G03X-1449569Y-62397I245J-51D01*
G02X-1449410Y-65279I769J-1403D01*
G03X-1450100Y-65732I-191J-462D01*
G02X-1450101Y-65745I-1600J31D01*
G03X-1449410Y-66221I500J-14D01*
G02X-1449486Y-69146I610J-1479D01*
G03X-1450200Y-69598I-214J-452D01*
G02X-1450207Y-69745I-1600J-2D01*
G03X-1449564Y-70269I498J-45D01*
G02X-1449722Y-73274I464J-1531D01*
G03X-1450413Y-73798I-194J-461D01*
G37*
G36*
G01X-1450500Y-82159D02*
G02X-1451338Y-80793I-1599J-41D01*
G03X-1450600Y-80341I238J440D01*
G02X-1450592Y-80142I1599J41D01*
G03X-1451306Y-79642I-498J49D01*
G02X-1450408Y-78358I-694J1442D01*
G03X-1449694Y-78858I498J-49D01*
G02X-1449762Y-81707I694J-1442D01*
G03X-1450500Y-82159I-238J-440D01*
G37*
G36*
G01X-744813Y-104625D02*
G02X-746998I-1093J-2304D01*
G03Y-103721I-214J452D01*
G02X-744813I1093J2304D01*
G03Y-104625I214J-452D01*
G37*
G36*
G01X-1614892D02*
G02X-1617077I-1093J-2304D01*
G03Y-103721I-214J452D01*
G02X-1614892I1093J2304D01*
G03Y-104625I214J-452D01*
G37*
G36*
G01X-388872Y-125896D02*
G02X-390538Y-125817I-898J-1324D01*
G03X-390498Y-124964I-240J439D01*
G02X-388832Y-125043I898J1324D01*
G03X-388872Y-125896I240J-439D01*
G37*
G36*
G01X-744813Y-132184D02*
G02X-746998I-1093J-2304D01*
G03Y-131280I-214J452D01*
G02Y-126672I1093J2304D01*
G03Y-125769I-214J452D01*
G02Y-121160I1093J2304D01*
G03Y-120257I-214J452D01*
G02X-744813I1093J2304D01*
G03Y-121160I214J-452D01*
G02Y-125769I-1093J-2304D01*
G03Y-126672I214J-452D01*
G02Y-131280I-1093J-2304D01*
G03Y-132184I214J-452D01*
G37*
G36*
G01X-1614892D02*
G02X-1617077I-1093J-2304D01*
G03Y-131280I-214J452D01*
G02Y-126672I1093J2304D01*
G03Y-125769I-214J452D01*
G02Y-121160I1093J2304D01*
G03Y-120257I-214J452D01*
G02X-1614892I1093J2304D01*
G03Y-121160I214J-452D01*
G02Y-125769I-1093J-2304D01*
G03Y-126672I214J-452D01*
G02Y-131280I-1093J-2304D01*
G03Y-132184I214J-452D01*
G37*
G36*
G01X-294341Y-138090D02*
G02X-296526I-1093J-2304D01*
G03Y-137186I-214J452D01*
G02X-294341I1093J2304D01*
G03Y-138090I214J-452D01*
G37*
G36*
G01X-1164419D02*
G02X-1166604I-1093J-2304D01*
G03Y-137186I-214J452D01*
G02X-1164419I1093J2304D01*
G03Y-138090I214J-452D01*
G37*
G36*
G01X-317963Y-143208D02*
G02X-320148I-1093J-2304D01*
G03Y-142304I-214J452D01*
G02Y-137696I1093J2304D01*
G03Y-136792I-214J452D01*
G02X-317963I1093J2304D01*
G03Y-137696I214J-452D01*
G02Y-142304I-1093J-2304D01*
G03Y-143208I214J-452D01*
G37*
G36*
G01X-1188041D02*
G02X-1190226I-1093J-2304D01*
G03Y-142304I-214J452D01*
G02Y-137696I1093J2304D01*
G03Y-136792I-214J452D01*
G02X-1188041I1093J2304D01*
G03Y-137696I214J-452D01*
G02Y-142304I-1093J-2304D01*
G03Y-143208I214J-452D01*
G37*
G36*
G01X-436518Y-147362D02*
G02X-438410Y-144838I-5412J-2087D01*
G03X-437619Y-144333I303J397D01*
G02X-435811Y-146743I3564J789D01*
G03X-436518Y-147362I-240J-438D01*
G37*
G36*
G01X-1306597D02*
G02X-1308489Y-144838I-5412J-2087D01*
G03X-1307698Y-144333I303J397D01*
G02X-1305890Y-146743I3564J789D01*
G03X-1306597Y-147362I-240J-438D01*
G37*
G36*
G01X-294341Y-154625D02*
G02X-296526I-1093J-2304D01*
G03Y-153721I-214J452D01*
G02X-294341I1093J2304D01*
G03Y-154625I214J-452D01*
G37*
G36*
G01X-310089D02*
G02X-312274I-1093J-2304D01*
G03Y-153721I-214J452D01*
G02Y-149113I1093J2304D01*
G03Y-148210I-214J452D01*
G02Y-143601I1093J2304D01*
G03Y-142698I-214J452D01*
G02Y-138090I1093J2304D01*
G03Y-137186I-214J452D01*
G02X-310089I1093J2304D01*
G03Y-138090I214J-452D01*
G02Y-142698I-1093J-2304D01*
G03Y-143601I214J-452D01*
G02Y-148210I-1093J-2304D01*
G03Y-149113I214J-452D01*
G02Y-153721I-1093J-2304D01*
G03Y-154625I214J-452D01*
G37*
G36*
G01X-1164419D02*
G02X-1166604I-1093J-2304D01*
G03Y-153721I-214J452D01*
G02X-1164419I1093J2304D01*
G03Y-154625I214J-452D01*
G37*
G36*
G01X-1180167D02*
G02X-1182352I-1093J-2304D01*
G03Y-153721I-214J452D01*
G02Y-149113I1093J2304D01*
G03Y-148210I-214J452D01*
G02Y-143601I1093J2304D01*
G03Y-142698I-214J452D01*
G02Y-138090I1093J2304D01*
G03Y-137186I-214J452D01*
G02X-1180167I1093J2304D01*
G03Y-138090I214J-452D01*
G02Y-142698I-1093J-2304D01*
G03Y-143601I214J-452D01*
G02Y-148210I-1093J-2304D01*
G03Y-149113I214J-452D01*
G02Y-153721I-1093J-2304D01*
G03Y-154625I214J-452D01*
G37*
G36*
G01X-302215Y-159743D02*
G02X-304400I-1093J-2304D01*
G03Y-158840I-214J452D01*
G02Y-154231I1093J2304D01*
G03Y-153328I-214J452D01*
G02Y-148720I1093J2304D01*
G03Y-147816I-214J452D01*
G02Y-143208I1093J2304D01*
G03Y-142304I-214J452D01*
G02Y-137696I1093J2304D01*
G03Y-136792I-214J452D01*
G02X-302215I1093J2304D01*
G03Y-137696I214J-452D01*
G02Y-142304I-1093J-2304D01*
G03Y-143208I214J-452D01*
G02Y-147816I-1093J-2304D01*
G03Y-148720I214J-452D01*
G02Y-153328I-1093J-2304D01*
G03Y-154231I214J-452D01*
G02Y-158840I-1093J-2304D01*
G03Y-159743I214J-452D01*
G37*
G36*
G01X-317963D02*
G02X-320148I-1093J-2304D01*
G03Y-158840I-214J452D01*
G02X-317963I1093J2304D01*
G03Y-159743I214J-452D01*
G37*
G36*
G01X-1172293D02*
G02X-1174478I-1093J-2304D01*
G03Y-158840I-214J452D01*
G02Y-154231I1093J2304D01*
G03Y-153328I-214J452D01*
G02Y-148720I1093J2304D01*
G03Y-147816I-214J452D01*
G02Y-143208I1093J2304D01*
G03Y-142304I-214J452D01*
G02Y-137696I1093J2304D01*
G03Y-136792I-214J452D01*
G02X-1172293I1093J2304D01*
G03Y-137696I214J-452D01*
G02Y-142304I-1093J-2304D01*
G03Y-143208I214J-452D01*
G02Y-147816I-1093J-2304D01*
G03Y-148720I214J-452D01*
G02Y-153328I-1093J-2304D01*
G03Y-154231I214J-452D01*
G02Y-158840I-1093J-2304D01*
G03Y-159743I214J-452D01*
G37*
G36*
G01X-1188041D02*
G02X-1190226I-1093J-2304D01*
G03Y-158840I-214J452D01*
G02X-1188041I1093J2304D01*
G03Y-159743I214J-452D01*
G37*
G36*
G01X-127569Y-171160D02*
G02X-129754I-1093J-2304D01*
G03Y-170257I-214J452D01*
G02X-127569I1093J2304D01*
G03Y-171160I214J-452D01*
G37*
G36*
G01X-997648D02*
G02X-999833I-1093J-2304D01*
G03Y-170257I-214J452D01*
G02X-997648I1093J2304D01*
G03Y-171160I214J-452D01*
G37*
G36*
G01X-276690Y-178957D02*
G02Y-177443I-1410J757D01*
G03X-275810I440J237D01*
G02Y-178957I1410J-757D01*
G03X-276690I-440J-237D01*
G37*
G36*
G01X-119695Y-176279D02*
G02X-121880I-1093J-2304D01*
G03Y-175375I-214J452D01*
G02X-119695I1093J2304D01*
G03Y-176279I214J-452D01*
G37*
G36*
G01X-989774D02*
G02X-991959I-1093J-2304D01*
G03Y-175375I-214J452D01*
G02X-989774I1093J2304D01*
G03Y-176279I214J-452D01*
G37*
G36*
G01X-1248991Y-179958D02*
G02X-1250200Y-178368I-1600J38D01*
G03X-1249578Y-177895I122J485D01*
G02X-1246560Y-177192I1600J-38D01*
G03X-1245682Y-177208I443J231D01*
G02X-1242793Y-177438I1391J-791D01*
G03X-1242043Y-177676I468J175D01*
G02X-1239679Y-178350I901J-1322D01*
G03X-1238929Y-178553I457J203D01*
G02X-1239455Y-180498I937J-1297D01*
G03X-1240205Y-180295I-457J-203D01*
G02X-1242640Y-179559I-937J1297D01*
G03X-1243390Y-179321I-468J-175D01*
G02X-1245710Y-178739I-901J1322D01*
G03X-1246588Y-178724I-443J-231D01*
G02X-1248369Y-179485I-1391J791D01*
G03X-1248991Y-179958I-122J-485D01*
G37*
G36*
G01X-1277879Y-180184D02*
G02X-1279022Y-179032I-1550J-395D01*
G03X-1278410Y-178425I127J484D01*
G02X-1277267Y-179577I1550J395D01*
G03X-1277879Y-180184I-127J-484D01*
G37*
G36*
G01X-378147Y-180281D02*
G02X-379660Y-179506I-1375J-819D01*
G03X-379274Y-178752I-43J498D01*
G02X-376482Y-177192I1375J819D01*
G03X-375604Y-177208I443J231D01*
G02X-372714Y-177438I1391J-791D01*
G03X-371964Y-177676I468J175D01*
G02X-369600Y-178350I901J-1322D01*
G03X-368850Y-178553I457J203D01*
G02X-369376Y-180498I937J-1297D01*
G03X-370126Y-180295I-457J-203D01*
G02X-372562Y-179559I-937J1297D01*
G03X-373312Y-179321I-468J-175D01*
G02X-375631Y-178739I-901J1322D01*
G03X-376509Y-178724I-443J-231D01*
G02X-377761Y-179527I-1391J791D01*
G03X-378147Y-180281I43J-498D01*
G37*
G36*
G01X-404627Y-181766D02*
G02X-406453I-913J-1314D01*
G03Y-180944I-285J411D01*
G02X-404627I913J1314D01*
G03Y-181766I285J-411D01*
G37*
G54D40*
X-1639488Y-27500D03*
X-1644488D03*
X-1654488Y-27300D03*
X-1649488Y-27400D03*
X-1634488Y-27600D03*
X-1629488Y-27700D03*
X-1618400Y-71600D03*
X-1618300Y-63100D03*
X-1621600Y-61100D03*
Y-65100D03*
X-1618500Y-67200D03*
X-1621600Y-69400D03*
X-1615000Y-37500D03*
Y-27500D03*
Y-32500D03*
X-1610000Y-37500D03*
Y-32500D03*
Y-27500D03*
X-1600000Y-37500D03*
Y-27500D03*
Y-32500D03*
X-1605000Y-37500D03*
Y-32500D03*
Y-27500D03*
X-1595000Y-37500D03*
Y-32500D03*
Y-27500D03*
X-1580000Y-42500D03*
Y-47500D03*
X-1585000Y-42500D03*
Y-47500D03*
X-1590000D03*
Y-42500D03*
X-1580000Y-27500D03*
Y-32500D03*
Y-37500D03*
X-1585000Y-32500D03*
Y-27500D03*
Y-37500D03*
X-1590000D03*
Y-32500D03*
Y-27500D03*
X-1565000Y-42500D03*
Y-47500D03*
X-1575000Y-42500D03*
Y-47500D03*
X-1570000Y-42500D03*
Y-47500D03*
X-1565000Y-27500D03*
Y-32500D03*
Y-37500D03*
X-1575000Y-27500D03*
Y-32500D03*
Y-37500D03*
X-1570000Y-32500D03*
Y-27500D03*
Y-37500D03*
X-1555000Y-47500D03*
Y-42500D03*
X-1550000Y-47500D03*
Y-42500D03*
X-1560000D03*
Y-47500D03*
X-1545000D03*
Y-42500D03*
Y-37500D03*
Y-32500D03*
Y-27500D03*
X-1555000Y-37500D03*
Y-32500D03*
Y-27500D03*
X-1550000Y-37500D03*
Y-32500D03*
Y-27500D03*
X-1560000D03*
Y-32500D03*
Y-37500D03*
X-1530000Y-120300D03*
X-1535000Y-42500D03*
Y-47500D03*
X-1540000Y-42500D03*
Y-47500D03*
X-1535000Y-32500D03*
X-1540000Y-37500D03*
Y-32500D03*
X-1535000Y-37500D03*
X-1497000Y-81700D03*
X-1496693Y-76890D03*
Y-71890D03*
X-1486693D03*
X-1491693D03*
X-1476693D03*
X-1481693D03*
X-1471693D03*
X-1476693Y-76890D03*
X-1481693D03*
X-1471693D03*
X-1466693D03*
Y-81890D03*
Y-71890D03*
X-1461693D03*
Y-76890D03*
X-1450000Y-175000D03*
X-1437500Y-162500D03*
X-1450000Y-150000D03*
Y-125000D03*
X-1443500Y-94000D03*
X-1450000Y-100000D03*
X-1448900Y-76100D03*
X-1434892Y-40389D03*
Y-50389D03*
Y-45389D03*
Y-35389D03*
X-1425000Y-175000D03*
X-1424500Y-100000D03*
X-1425000Y-87500D03*
Y-62500D03*
X-1419892Y-50389D03*
Y-40389D03*
Y-45389D03*
X-1427392Y-50389D03*
Y-45389D03*
Y-40389D03*
X-1419892Y-35389D03*
X-1427392D03*
X-1432000Y-18000D03*
X-1412500Y-162500D03*
X-1412000Y-87000D03*
X-1412500Y-75000D03*
X-1404892Y-50389D03*
Y-45389D03*
Y-40389D03*
X-1412392Y-50389D03*
Y-45389D03*
Y-40389D03*
X-1404892Y-35389D03*
X-1412392D03*
X-1407000Y-18000D03*
X-1407500Y14500D03*
X-1400000Y-175000D03*
X-1387500Y-162500D03*
X-1400000Y-150000D03*
X-1387500Y-137500D03*
X-1400000Y-125000D03*
X-1387500Y-112500D03*
X-1400500Y-87000D03*
X-1391000Y-96500D03*
X-1387500Y-75000D03*
X-1400000Y-62500D03*
X-1389892Y-40389D03*
Y-45389D03*
Y-50389D03*
X-1397392Y-40389D03*
Y-45389D03*
Y-50389D03*
X-1389892Y-35389D03*
X-1397392D03*
X-1395000Y-8000D03*
X-1375000Y-62500D03*
X-1382392Y-40389D03*
Y-45389D03*
Y-50389D03*
Y-35389D03*
X-1382500Y-18000D03*
Y-500D03*
Y14500D03*
X-1362500Y-75000D03*
X-1370000Y-8000D03*
X-1357500Y-500D03*
X-1370000Y7000D03*
X-1357500Y14500D03*
X-1350000Y-62500D03*
X-1345000Y-8000D03*
Y7000D03*
X-1335400Y-75000D03*
Y-37600D03*
X-1332500Y-500D03*
Y14500D03*
X-1322228Y-88400D03*
X-1316728Y-89200D03*
X-1321000Y-94850D03*
X-1317700Y-72700D03*
X-1310559Y-74200D03*
X-1317700Y-60200D03*
X-1310559Y-68700D03*
Y-63200D03*
Y-57700D03*
Y-41200D03*
Y-52200D03*
X-1311200Y-30200D03*
X-1310559Y-35700D03*
X-1320000Y7000D03*
X-1318500Y-6000D03*
X-1306850Y-95000D03*
X-1300350Y-88500D03*
X-1293500Y-80000D03*
X-1302400Y-84100D03*
X-1297995Y-58405D03*
X-1298400Y-63200D03*
X-1298780Y-52200D03*
X-1298000Y-41200D03*
X-1298700Y-35700D03*
X-1295400Y-13400D03*
X-1307500Y14500D03*
X-1282500D03*
X-1248860Y-150200D03*
X-1246390Y-153490D03*
X-1249016Y-144800D03*
X-1250660Y-140480D03*
X-1257500Y-45000D03*
Y-20000D03*
Y14500D03*
X-1236310Y-140390D03*
X-1232500Y-20000D03*
Y14500D03*
X-1202580Y-176300D03*
X-1202100Y-103200D03*
X-1199500Y-3000D03*
X-1207500Y14500D03*
X-1191200Y-40500D03*
X-1191000Y-46500D03*
X-1191900Y-29500D03*
X-1190800Y-23450D03*
X-1191200Y-12128D03*
X-1192359Y-5800D03*
X-1191500Y0D03*
X-1176100Y-114800D03*
X-1170300Y-114600D03*
X-1172500Y-44000D03*
X-1173200Y-49700D03*
X-1178900Y-46700D03*
X-1172500Y-38500D03*
X-1178950Y-23250D03*
X-1171800Y-26950D03*
X-1178800Y-34800D03*
X-1177800Y-12100D03*
X-1171800Y-16250D03*
X-1178800Y-5800D03*
X-1172100Y-5400D03*
X-1182500Y14500D03*
X-1160000Y-115100D03*
X-1154200Y-103100D03*
X-1154400Y-107900D03*
X-1159700Y-43900D03*
X-1160150Y-26750D03*
X-1159800Y-33100D03*
X-1151500Y-15000D03*
X-1158700Y-16250D03*
X-1159700Y-5750D03*
X-1157500Y14500D03*
X-1137500Y-15000D03*
X-1124700Y-180000D03*
X-1134579Y-179850D03*
X-1125000Y-101700D03*
X-1121870Y-104330D03*
X-1126000Y-2500D03*
X-1132500Y14500D03*
X-1113328Y-182209D03*
X-1107828Y-182300D03*
X-1114979Y-170700D03*
X-1106979D03*
X-1114500Y-129000D03*
X-1110500D03*
X-1115490Y-104240D03*
X-1118701Y-101759D03*
X-1112402Y-101600D03*
X-1109300Y-104200D03*
X-1106102Y-102100D03*
X-1107700Y-73400D03*
Y-63100D03*
X-1107800Y-68200D03*
X-1111500Y-15000D03*
X-1107500Y14500D03*
X-1095600Y-179600D03*
X-1102953Y-104200D03*
X-1099400Y-90200D03*
X-1093400D03*
X-1100000Y-2500D03*
X-1084600Y-179850D03*
X-1073000Y-90300D03*
X-1082500Y14500D03*
X-1056900Y-56300D03*
X-1063600Y-56600D03*
X-1062000Y-29200D03*
X-1061900Y-5200D03*
X-1070000Y14500D03*
X-1045100Y-52900D03*
X-1044300Y-47661D03*
X-1051200Y-44100D03*
X-1054900Y-29800D03*
X-1045400Y-38000D03*
X-1051400Y-26000D03*
X-1047289Y-26300D03*
X-1041300Y-10100D03*
Y-16500D03*
X-1054600Y-5100D03*
X-1050811Y2600D03*
X-1047300Y-2700D03*
X-1045000Y14500D03*
X-1033843Y-128576D03*
X-1017670Y-123250D03*
X-1022140Y-122960D03*
X-1020000Y14500D03*
X-997500Y-7500D03*
X-995000Y14500D03*
X-970000Y-7500D03*
Y14500D03*
X-945000Y-7500D03*
Y14500D03*
X-922500Y-159500D03*
Y-132500D03*
Y-107500D03*
Y-82500D03*
Y-57500D03*
Y-7500D03*
X-922000Y14500D03*
X-910000Y-170000D03*
Y-95000D03*
Y-70000D03*
Y-45000D03*
Y-20000D03*
Y5000D03*
X-885000Y-170000D03*
X-897500Y-159500D03*
Y-132500D03*
Y-107500D03*
X-885000Y-95000D03*
X-897500Y-82500D03*
X-885000Y-70000D03*
X-897500Y-57500D03*
X-885000Y-45000D03*
Y-20000D03*
X-897500Y-7500D03*
X-885000Y5000D03*
X-897500Y14500D03*
X-872500Y-159500D03*
Y-132500D03*
Y-107500D03*
Y-82500D03*
Y-57500D03*
Y-7500D03*
Y14500D03*
X-860000Y-170000D03*
Y-95000D03*
Y-70000D03*
Y-45000D03*
Y-20000D03*
Y5000D03*
X-847500Y-159500D03*
Y-132500D03*
Y-107500D03*
Y-82500D03*
Y-57500D03*
Y-7500D03*
X-848000Y14500D03*
X-822500Y-159500D03*
Y-132500D03*
X-835000Y-120000D03*
X-822500Y-107500D03*
X-835000Y-95000D03*
X-822500Y-82500D03*
X-835000Y-70000D03*
X-822500Y-57500D03*
X-835000Y-45000D03*
X-822500Y-7500D03*
X-835000Y-20000D03*
X-822500Y14500D03*
X-810000Y-20000D03*
Y5000D03*
X-797500Y-7500D03*
Y14500D03*
X-785000Y-20000D03*
Y5000D03*
X-760000Y-145000D03*
X-772500Y-132500D03*
X-760000Y-120000D03*
X-772500Y-107500D03*
X-760000Y-95000D03*
X-772500Y-82500D03*
X-760000Y-70000D03*
X-772500Y-57500D03*
X-760000Y-45000D03*
Y-20000D03*
X-772500Y-7500D03*
X-760000Y5000D03*
X-772500Y14500D03*
X-747500Y-57500D03*
Y-7500D03*
Y14500D03*
X-735000Y-45000D03*
Y-20000D03*
Y5000D03*
X-722500Y-57500D03*
Y-7500D03*
Y14500D03*
X-710000Y-45000D03*
X-697500Y-7500D03*
X-710000Y-20000D03*
Y5000D03*
X-697500Y14500D03*
X-685000Y-45000D03*
Y-20000D03*
Y5000D03*
X-672500Y-7500D03*
Y14500D03*
X-649700Y-117200D03*
X-655500Y-25500D03*
X-642500D03*
Y-37500D03*
Y-12500D03*
X-645000Y14500D03*
X-626625Y-81614D03*
X-626614Y-76890D03*
Y-71890D03*
X-621614D03*
X-616614D03*
X-630000Y-37500D03*
X-616000Y-25500D03*
X-606614Y-71890D03*
X-611614D03*
X-601614D03*
X-606614Y-76890D03*
X-611614D03*
X-601614D03*
X-602500Y-25000D03*
Y0D03*
X-591200Y-179700D03*
X-591614Y-71890D03*
X-596614Y-76890D03*
Y-81890D03*
X-591614Y-76890D03*
X-596614Y-71890D03*
X-590000Y-37500D03*
Y-12500D03*
Y12500D03*
X-577500Y-165000D03*
Y-140000D03*
Y-115000D03*
Y-65000D03*
Y-25000D03*
Y0D03*
X-565000Y-177500D03*
Y-152500D03*
Y-37500D03*
Y-12500D03*
Y12500D03*
X-540000Y-177500D03*
X-552500Y-165000D03*
X-540000Y-152500D03*
X-552500Y-140000D03*
X-540000Y-127500D03*
Y-102500D03*
Y-77500D03*
X-552500Y-65000D03*
Y-25000D03*
X-540000Y-37500D03*
Y-12500D03*
X-552500Y0D03*
X-540000Y12500D03*
X-527500Y-165000D03*
Y-140000D03*
Y-115000D03*
Y-90000D03*
Y-65000D03*
Y-25000D03*
Y0D03*
X-515000Y-177500D03*
Y-152500D03*
Y-127500D03*
Y-102500D03*
Y-77500D03*
Y-37500D03*
Y-12500D03*
Y12500D03*
X-490000Y-102500D03*
X-502500Y-90000D03*
X-490000Y-77500D03*
X-502500Y-65000D03*
X-490000Y-37500D03*
X-502500Y-25000D03*
X-490000Y-12500D03*
X-502500Y0D03*
X-490000Y12500D03*
X-477500Y-25000D03*
Y0D03*
X-462000Y-73500D03*
X-465000Y-37500D03*
Y12500D03*
X-453628Y-88300D03*
X-448128Y-88800D03*
X-452700Y-69000D03*
X-449100Y-60841D03*
X-442800Y-46600D03*
X-449000Y6500D03*
X-448600Y-5900D03*
X-432118Y-87082D03*
X-436771Y-92400D03*
X-441959Y-74100D03*
X-429900Y-79600D03*
X-441959Y-68600D03*
X-429000Y-57600D03*
X-430700Y-63100D03*
X-441959D03*
Y-57600D03*
X-430180Y-52100D03*
X-429400Y-41100D03*
X-441959D03*
Y-52100D03*
X-430400Y-35600D03*
X-441959D03*
X-431000Y6500D03*
X-440000Y12500D03*
X-424500Y-26500D03*
X-424600Y-14400D03*
X-380421Y-147000D03*
X-375800Y-154000D03*
X-373620Y-124430D03*
X-374800Y-105700D03*
X-333450Y-174950D03*
X-321600Y-113500D03*
X-316500D03*
X-321700Y-42000D03*
X-321500Y-47500D03*
X-322400Y-31000D03*
X-321300Y-24950D03*
X-321800Y-7300D03*
X-321700Y-13628D03*
X-321859Y-1500D03*
X-312100Y-113500D03*
X-303200Y-43300D03*
Y-48800D03*
X-309400Y-47700D03*
X-302300Y-25950D03*
X-302900Y-37900D03*
X-309400Y-25100D03*
X-308500Y-36400D03*
X-308800Y-7400D03*
X-302500Y-15200D03*
X-307900Y-13628D03*
X-302300Y-4450D03*
X-286500Y-113700D03*
X-296400Y-113500D03*
X-290400Y-43200D03*
X-289500Y-32500D03*
X-290800Y-26000D03*
X-290700Y-9750D03*
X-290300Y-4400D03*
X-282300Y-113700D03*
X-254800Y-180000D03*
X-265200Y-179850D03*
X-254921Y-101700D03*
X-237750Y-182300D03*
X-243250Y-182209D03*
X-244900Y-170700D03*
X-244300Y-129300D03*
X-240300D03*
X-245411Y-104240D03*
X-248622Y-101759D03*
X-251792Y-104330D03*
X-242323Y-101600D03*
X-239222Y-104200D03*
X-225400Y-179800D03*
X-236900Y-170700D03*
X-236024Y-102100D03*
X-232874Y-104200D03*
X-214500Y-179800D03*
X-196900Y-176500D03*
X-201600Y-176600D03*
X-206100D03*
X-191000Y-56400D03*
X-190300Y-28900D03*
Y-4200D03*
X-185900Y-56200D03*
X-179800Y-43500D03*
X-182900Y-29800D03*
X-176350Y-27200D03*
X-179811Y-21300D03*
X-183200Y-4600D03*
X-179011Y4500D03*
X-175100Y-1800D03*
X-163764Y-128576D03*
X-173800Y-47300D03*
X-173200Y-52400D03*
X-170200Y-34470D03*
X-170500Y-10000D03*
X-170300Y-16500D03*
X-150900Y-121100D03*
X-152400Y-125050D03*
G54D41*
X-1615984Y-156535D03*
X-745906D03*
G54D42*
X-994488Y-93068D03*
Y-78108D03*
Y-63147D03*
Y-48187D03*
X-991535Y-98580D03*
Y-83620D03*
Y-68659D03*
Y-53698D03*
X-951181Y-93068D03*
X-948228Y-98580D03*
Y-83620D03*
X-951181Y-78108D03*
X-948228Y-68659D03*
X-951181Y-63147D03*
X-948228Y-53698D03*
X-951181Y-48187D03*
X-121457Y-98580D03*
X-124409Y-93068D03*
X-121457Y-83620D03*
X-124409Y-78108D03*
X-121457Y-68659D03*
X-124409Y-63147D03*
X-121457Y-53698D03*
X-124409Y-48187D03*
X-81102Y-93068D03*
Y-78108D03*
Y-63147D03*
Y-48187D03*
X-78150Y-98580D03*
Y-83620D03*
Y-68659D03*
Y-53698D03*
G54D38*
X-1649000Y-105752D03*
Y-113626D03*
X-793728Y-153976D03*
Y-146102D03*
G54D37*
X-1649000Y-121500D03*
X-1296260Y-175039D03*
X-1304134D03*
X-1296260Y-167165D03*
X-1304134D03*
X-1296260Y-159291D03*
X-1304134D03*
X-1296260Y-143543D03*
Y-135669D03*
X-1304134D03*
X-1296260Y-127795D03*
X-1304134D03*
X-793728Y-161850D03*
X-426181Y-175039D03*
X-434055D03*
X-426181Y-167165D03*
X-434055D03*
X-426181Y-159291D03*
X-434055D03*
X-426181Y-143543D03*
Y-135669D03*
X-434055D03*
X-426181Y-127795D03*
X-434055D03*
G54D33*
X-1488693Y-178940D03*
X-1476693Y-64840D03*
X-618614Y-178940D03*
X-606614Y-64840D03*
G54D39*
X-1649000Y-97878D03*
X-793728Y-138228D03*
G54D31*
X-341929Y-142362D03*
X-408071D03*
X-1212008D03*
X-1278150D03*
G54D44*
X-806854Y-83100D03*
X-785200D03*
G54D43*
X-806854Y-99635D03*
X-785200D03*
G54D36*
X-1094291Y-126220D03*
X-224213D03*
G54D35*
X-1132087D03*
X-262008D03*
G54D34*
X-1410000Y0D03*
X0Y-136453D03*
X0Y0D03*
G54D32*
X-486810Y-167165D03*
X-1051613D03*
Y-118937D03*
X-486810D03*
X-181534Y-167165D03*
Y-118937D03*
%LPD*%
G75*
G54D10*
X-1645906Y-167953D03*
X-1522728Y-154950D03*
X-1047676Y-78740D03*
X-652638Y-154950D03*
X-177597Y-78740D03*
X6890Y-167953D03*
G54D11*
X-1656906D03*
X-1645906Y-178953D03*
X-1653906Y-175453D03*
X-1653406Y-159953D03*
X-1645906Y-156953D03*
X-1634906Y-167953D03*
X-1637906Y-175453D03*
X-1638406Y-159953D03*
X-1530728Y-162450D03*
X-1533728Y-154950D03*
X-1530228Y-146950D03*
X-1522728Y-165950D03*
X-1514728Y-162450D03*
X-1515228Y-146950D03*
X-1522728Y-143950D03*
X-1511728Y-154950D03*
X-1058676Y-78740D03*
X-1047676Y-89740D03*
X-1055676Y-86240D03*
X-1055176Y-70740D03*
X-1047676Y-67740D03*
X-1039676Y-86240D03*
X-1040176Y-70740D03*
X-1036676Y-78740D03*
X-663638Y-154950D03*
X-652638Y-165950D03*
X-660638Y-162450D03*
X-660138Y-146950D03*
X-652638Y-143950D03*
X-641638Y-154950D03*
X-644638Y-162450D03*
X-645138Y-146950D03*
X-177597Y-89740D03*
X-185597Y-86240D03*
X-188597Y-78740D03*
X-185097Y-70740D03*
X-177597Y-67740D03*
X-169597Y-86240D03*
X-170097Y-70740D03*
X-166597Y-78740D03*
X-4110Y-167953D03*
X6890Y-178953D03*
X-1110Y-175453D03*
X14390Y-159953D03*
X-610D03*
X6890Y-156953D03*
X17890Y-167953D03*
X14890Y-175453D03*
G54D20*
X-1025000Y-50942D03*
Y1459D03*
X-1015157Y-105312D03*
X-997441D03*
X-981693Y-50942D03*
Y1459D03*
X-971850Y-105312D03*
X-954134D03*
X-938386Y-50942D03*
Y1459D03*
X-145079Y-105312D03*
X-154921Y-50942D03*
Y1459D03*
X-127362Y-105312D03*
X-111614Y-50942D03*
Y1459D03*
X-101772Y-105312D03*
X-84055D03*
X-68307Y-50942D03*
Y1459D03*
G54D30*
G01X-1020800Y-457700D02*
G02X-1020300Y-458200I0J-500D01*
G01Y-458400D01*
G02X-1020900Y-459000I-600J0D01*
G01X-1021300D01*
G01X-1021800Y-460500D02*
Y-457700D01*
X-1020600D01*
G01X-1018340Y-459100D02*
G03I-2660J0D01*
G01X-1020700D02*
X-1020200Y-460500D01*
G54D21*
X-1015157Y-95824D03*
Y-80864D03*
Y-65903D03*
Y-50942D03*
X-1006299Y-95824D03*
X-997441D03*
X-1006299Y-80864D03*
X-997441D03*
X-1006299Y-65903D03*
X-997441D03*
X-1006299Y-50942D03*
X-997441D03*
X-971850Y-95824D03*
X-962992D03*
X-971850Y-80864D03*
X-962992D03*
X-971850Y-65903D03*
X-962992D03*
X-971850Y-50942D03*
X-962992D03*
X-954134Y-95824D03*
Y-80864D03*
Y-65903D03*
Y-50942D03*
X-145079Y-95824D03*
Y-80864D03*
Y-65903D03*
Y-50942D03*
X-136220Y-95824D03*
X-127362D03*
X-136220Y-80864D03*
X-127362D03*
X-136220Y-65903D03*
X-127362D03*
X-136220Y-50942D03*
X-127362D03*
X-101772Y-95824D03*
Y-80864D03*
Y-65903D03*
Y-50942D03*
X-92913Y-95824D03*
X-84055D03*
X-92913Y-80864D03*
X-84055D03*
X-92913Y-65903D03*
X-84055D03*
X-92913Y-50942D03*
X-84055D03*
G54D12*
X-1656000Y-135000D03*
X-1658500Y-31000D03*
X-1633000Y-135500D03*
X-1535063Y-22160D03*
X-1530063Y-12160D03*
Y-17160D03*
Y-22160D03*
X-1535063Y-12160D03*
Y-17160D03*
X-1524359Y-125359D03*
X-1515063Y-12160D03*
Y-17160D03*
Y-22160D03*
X-1525063Y-12160D03*
Y-17160D03*
X-1520063Y-12160D03*
Y-17160D03*
X-1525063Y-22160D03*
X-1520063D03*
X-1497043Y-169390D03*
X-1500063Y-12160D03*
Y-17160D03*
Y-22160D03*
X-1510063Y-12160D03*
Y-17160D03*
X-1505063Y-12160D03*
Y-17160D03*
X-1510063Y-22160D03*
X-1505063D03*
X-1497043Y-164390D03*
X-1486693Y-166890D03*
X-1497043Y-149390D03*
X-1486693Y-161890D03*
X-1491652Y-151849D03*
X-1491693Y-156890D03*
X-1497043Y-144390D03*
X-1491693Y-136890D03*
X-1486693Y-141890D03*
Y-146890D03*
X-1497043Y-124390D03*
Y-129390D03*
X-1486693Y-121890D03*
Y-126890D03*
X-1491693Y-131890D03*
X-1497043Y-109390D03*
Y-104390D03*
X-1486693Y-101890D03*
Y-106890D03*
X-1491693Y-111890D03*
Y-116890D03*
X-1497043Y-89390D03*
X-1486693Y-86890D03*
X-1491693Y-91890D03*
Y-96890D03*
X-1486693Y-76890D03*
X-1491693D03*
X-1486693Y-81890D03*
X-1485063Y-12160D03*
Y-17160D03*
Y-22160D03*
X-1495063Y-12160D03*
Y-17160D03*
X-1490063Y-12160D03*
Y-17160D03*
X-1495063Y-22160D03*
X-1490063D03*
X-1466693Y-166890D03*
X-1476693D03*
Y-161890D03*
X-1481693Y-156890D03*
Y-151890D03*
X-1471693D03*
Y-156890D03*
X-1466693Y-161890D03*
X-1481693Y-136890D03*
X-1471693D03*
X-1466693Y-141890D03*
X-1476693D03*
X-1466693Y-146890D03*
X-1476693D03*
X-1481693Y-131890D03*
X-1466693Y-121890D03*
X-1476693D03*
X-1466693Y-126890D03*
X-1476693D03*
X-1471693Y-131890D03*
X-1481693Y-111890D03*
Y-116890D03*
X-1466693Y-101890D03*
X-1476693D03*
X-1466693Y-106890D03*
X-1476693D03*
X-1471693Y-111890D03*
Y-116890D03*
X-1481693Y-91890D03*
Y-96890D03*
X-1466693Y-86890D03*
X-1476693D03*
X-1471693Y-91890D03*
Y-96890D03*
X-1476693Y-81890D03*
X-1475063Y-22160D03*
X-1470063Y-12160D03*
Y-17160D03*
Y-22160D03*
X-1480063Y-12160D03*
Y-17160D03*
X-1475063Y-12160D03*
Y-17160D03*
X-1480063Y-22160D03*
X-1461693Y-151890D03*
Y-156890D03*
Y-136890D03*
Y-131890D03*
X-1450000Y-112500D03*
X-1461693Y-111890D03*
Y-116890D03*
Y-91890D03*
Y-96890D03*
X-1465063Y-12160D03*
Y-17160D03*
Y-22160D03*
X-1437500Y-175000D03*
X-1450000Y-162500D03*
Y-137500D03*
X-1437500Y-100000D03*
X-1436500Y-87500D03*
X-1450000D03*
X-1435000Y1000D03*
X-1425000Y-162500D03*
X-1430500Y-93500D03*
X-1430000Y-75400D03*
X-1421250Y-81250D03*
X-1431500Y-81000D03*
X-1419500Y-18000D03*
X-1420000Y14500D03*
X-1412500Y-175000D03*
X-1406250Y-106250D03*
X-1412000Y-100500D03*
X-1418500Y-93500D03*
X-1406250Y-82500D03*
X-1412500Y-62500D03*
X-1387500Y-175000D03*
Y-150000D03*
X-1400000Y-162500D03*
X-1387300Y-133200D03*
X-1387500Y-125000D03*
X-1400100Y-131550D03*
X-1395000Y-106250D03*
X-1400000Y-112500D03*
X-1400500Y-96500D03*
X-1393750Y-82500D03*
X-1400000Y-75000D03*
X-1387500Y-62500D03*
X-1394500Y-18000D03*
X-1395000Y-500D03*
X-1395518Y14053D03*
X-1371250Y-112500D03*
X-1380000Y-106250D03*
X-1381250Y-82500D03*
X-1375000Y-75000D03*
X-1373800Y-52900D03*
X-1382500Y-8000D03*
Y7000D03*
X-1363750Y-106250D03*
X-1356250Y-82500D03*
X-1368750D03*
X-1362500Y-62500D03*
X-1356700Y-25600D03*
X-1357500Y-8000D03*
X-1370000Y-500D03*
X-1357500Y7000D03*
X-1370000Y14500D03*
X-1350600Y-75000D03*
X-1343200Y-82700D03*
X-1345000Y-500D03*
Y14500D03*
X-1330400Y-74900D03*
X-1324840Y-82120D03*
X-1337500Y-62500D03*
X-1324500Y-26959D03*
X-1332500Y-27500D03*
Y7000D03*
X-1313040Y-80810D03*
X-1310600Y-46690D03*
X-1320000Y-500D03*
Y14500D03*
X-1298800Y-30200D03*
X-1307500Y7000D03*
X-1295000Y14500D03*
X-1271813Y-181337D03*
X-1264267Y-181074D03*
X-1271813Y-185937D03*
X-1264013D03*
X-1263189Y-177998D03*
X-1272638D03*
X-1274213Y-157350D03*
X-1264764D03*
X-1265588Y-154080D03*
X-1273388D03*
Y-149480D03*
X-1265588D03*
X-1263925Y-146735D03*
X-1264060Y-141950D03*
X-1270000Y14500D03*
X-1248010Y-184405D03*
Y-192205D03*
X-1253740Y-177998D03*
X-1255315Y-157350D03*
X-1256125Y-146735D03*
Y-142135D03*
X-1257500Y-57500D03*
X-1230040Y-183080D03*
Y-187680D03*
X-1237840Y-183080D03*
Y-187680D03*
X-1243410Y-184405D03*
Y-192205D03*
X-1234843Y-177998D03*
X-1236418Y-157350D03*
X-1235593Y-136650D03*
Y-132050D03*
X-1245000Y-70000D03*
X-1232500Y-57500D03*
Y-45000D03*
X-1245000D03*
Y-20000D03*
Y14500D03*
X-1215945Y-177998D03*
X-1225394D03*
X-1217520Y-157350D03*
X-1226969D03*
X-1218290Y-152200D03*
X-1226090D03*
X-1218290Y-147600D03*
X-1226090D03*
X-1227793Y-136650D03*
Y-132050D03*
X-1220000Y14500D03*
X-1211720Y-169660D03*
Y-165060D03*
X-1203920D03*
Y-169660D03*
X-1199500Y5400D03*
X-1191500Y-34000D03*
X-1191000Y-18250D03*
X-1195000Y14500D03*
X-1179000Y-40500D03*
X-1172000Y-10750D03*
X-1171500Y-21750D03*
X-1170000Y14500D03*
X-1160000Y-38500D03*
X-1137500Y-2500D03*
X-1145000Y14500D03*
X-1124878Y-175150D03*
X-1124900Y-170650D03*
X-1125750Y-152883D03*
Y-157483D03*
X-1126575Y-147990D03*
Y-136730D03*
X-1124800Y-129000D03*
X-1120400D03*
X-1128810Y-104171D03*
X-1126000Y-15000D03*
X-1120000Y14500D03*
X-1117950Y-157483D03*
Y-152883D03*
X-1117126Y-136730D03*
X-1107677Y-148090D03*
Y-136730D03*
X-1117126Y-148090D03*
X-1111003Y-123960D03*
X-1106403D03*
Y-116160D03*
X-1111003D03*
X-1111500Y-2500D03*
X-1096278Y-170650D03*
X-1096200Y-175150D03*
X-1098228Y-148090D03*
Y-136730D03*
X-1099010Y-104183D03*
X-1100000Y-15000D03*
X-1095000Y14500D03*
X-1032500D03*
X-1015729Y-100550D03*
X-1012638Y-85886D03*
X-1015179Y-74100D03*
X-1012638Y-70873D03*
Y-56060D03*
X-1012860Y-41250D03*
X-1012500Y-7500D03*
X-1003380Y-86986D03*
X-1008429Y-91400D03*
X-999960Y-90706D03*
X-996670Y-75460D03*
X-1008719Y-75998D03*
X-999860Y-75848D03*
Y-60885D03*
X-1003780Y-56060D03*
X-994280Y-40890D03*
X-1007500Y14500D03*
X-983000Y-7500D03*
X-982500Y14500D03*
X-969331Y-100849D03*
Y-85886D03*
X-965512Y-90706D03*
X-971779Y-73800D03*
X-965412Y-75848D03*
Y-45922D03*
X-956653Y-90706D03*
X-960273Y-101049D03*
X-953250Y-75340D03*
X-956553Y-75848D03*
X-957779Y-57700D03*
X-956553Y-60885D03*
Y-45922D03*
X-957500Y-7500D03*
Y14500D03*
X-932500Y-7500D03*
Y14500D03*
X-922500Y-170000D03*
Y-120000D03*
Y-95000D03*
Y-70000D03*
Y-45000D03*
Y-20000D03*
Y5000D03*
X-910000Y-159500D03*
Y-132500D03*
Y-107500D03*
Y-82500D03*
Y-57500D03*
Y-7500D03*
X-909500Y14500D03*
X-897500Y-170000D03*
X-885000Y-159500D03*
Y-132500D03*
Y-107500D03*
X-897500Y-95000D03*
X-885000Y-82500D03*
X-897500Y-70000D03*
X-885000Y-57500D03*
X-897500Y-45000D03*
X-885000Y-7500D03*
X-897500Y-20000D03*
Y5000D03*
X-885000Y14500D03*
X-872500Y-170000D03*
Y-95000D03*
Y-70000D03*
Y-45000D03*
Y-20000D03*
Y5000D03*
X-860000Y-159500D03*
Y-132500D03*
Y-107500D03*
Y-82500D03*
Y-57500D03*
Y-7500D03*
Y14500D03*
X-847500Y-170000D03*
Y-95000D03*
Y-70000D03*
Y-45000D03*
Y-20000D03*
Y5000D03*
X-822500Y-170000D03*
X-835000Y-159500D03*
X-822500Y-145000D03*
X-835000Y-132500D03*
X-822500Y-120000D03*
X-835000Y-107500D03*
X-822500Y-95000D03*
X-835000Y-82500D03*
X-822500Y-70000D03*
X-835000Y-57500D03*
X-822500Y-45000D03*
Y-20000D03*
Y5000D03*
X-835500Y14500D03*
X-810000Y-170000D03*
Y-157500D03*
Y-145000D03*
Y-132500D03*
Y-120000D03*
Y-70000D03*
Y-57500D03*
Y-45000D03*
Y-7500D03*
Y14500D03*
X-797500Y-120000D03*
Y-70000D03*
Y-57500D03*
Y-45000D03*
Y-20000D03*
Y5000D03*
X-785500Y-120000D03*
X-785000Y-70000D03*
Y-57500D03*
Y-45000D03*
Y-7500D03*
Y14500D03*
X-772500Y-170000D03*
Y-145000D03*
X-760000Y-132500D03*
X-772500Y-120000D03*
X-760000Y-107500D03*
X-772500Y-95000D03*
X-760000Y-82500D03*
X-772500Y-70000D03*
X-760000Y-57500D03*
X-772500Y-45000D03*
X-760000Y-7500D03*
X-772500Y-20000D03*
Y5000D03*
X-760000Y14500D03*
X-747500Y-45000D03*
Y-20000D03*
Y5000D03*
X-735000Y-57500D03*
Y-7500D03*
Y14500D03*
X-722500Y-45000D03*
Y-20000D03*
Y5000D03*
X-697500Y-45000D03*
Y-20000D03*
X-710000Y-7500D03*
X-697500Y5000D03*
X-710000Y14500D03*
X-685000Y-7500D03*
Y14500D03*
X-672500Y-45000D03*
Y-20000D03*
Y5000D03*
X-655500Y-37500D03*
Y-12500D03*
Y-500D03*
X-660000Y14500D03*
X-643700Y-125400D03*
X-632500Y14500D03*
X-626964Y-169390D03*
Y-164390D03*
X-616614Y-166890D03*
X-621614Y-156890D03*
X-621573Y-151849D03*
X-616614Y-161890D03*
X-627200Y-151300D03*
X-621614Y-136890D03*
X-616614Y-146890D03*
Y-141890D03*
X-626900Y-141300D03*
X-621614Y-131890D03*
X-616614Y-126890D03*
Y-121890D03*
X-621614D03*
X-628700Y-130100D03*
X-621614Y-116890D03*
Y-111890D03*
X-626964Y-104390D03*
Y-109390D03*
X-616614Y-106890D03*
Y-101890D03*
X-621614Y-96890D03*
Y-91890D03*
X-626964Y-89390D03*
X-616614Y-86890D03*
Y-76890D03*
X-621614D03*
X-616614Y-81890D03*
X-616000Y-37500D03*
X-630000Y-25500D03*
Y-12500D03*
X-616000D03*
Y14500D03*
X-606614Y-166890D03*
X-601614Y-156890D03*
Y-151890D03*
X-611614D03*
Y-156890D03*
X-606614Y-161890D03*
Y-146890D03*
Y-141890D03*
X-601614Y-136890D03*
X-611614D03*
X-601614Y-131890D03*
X-606614Y-126890D03*
Y-121890D03*
X-611614Y-131890D03*
X-601614Y-116890D03*
Y-111890D03*
X-606614Y-106890D03*
Y-101890D03*
X-611614Y-116890D03*
Y-111890D03*
X-601614Y-96890D03*
Y-91890D03*
X-606614Y-86890D03*
X-611614Y-96890D03*
Y-91890D03*
X-606614Y-81890D03*
X-602500Y-37500D03*
Y-12500D03*
Y12500D03*
X-596614Y-166890D03*
X-591614Y-156890D03*
Y-151890D03*
X-596614Y-161890D03*
X-591614Y-136890D03*
X-596614Y-146890D03*
Y-141890D03*
X-591614Y-131890D03*
X-596614Y-126890D03*
Y-121890D03*
X-591614Y-116890D03*
Y-111890D03*
X-596614Y-106890D03*
Y-101890D03*
X-591614Y-96890D03*
Y-91890D03*
X-596614Y-86890D03*
X-590000Y-25000D03*
Y0D03*
X-577500Y-177500D03*
Y-152500D03*
Y-127500D03*
Y-37500D03*
Y-12500D03*
Y12500D03*
X-565000Y-165000D03*
Y-140000D03*
Y-65000D03*
Y-25000D03*
Y0D03*
X-540000Y-165000D03*
X-552500Y-177500D03*
Y-152500D03*
X-540000Y-140000D03*
Y-115000D03*
Y-90000D03*
Y-65000D03*
Y-25000D03*
X-552500Y-37500D03*
Y-12500D03*
X-540000Y0D03*
X-552500Y12500D03*
X-527500Y-177500D03*
Y-152500D03*
Y-127500D03*
Y-102500D03*
Y-77500D03*
Y-37500D03*
Y-12500D03*
Y12500D03*
X-515000Y-165000D03*
Y-140000D03*
Y-115000D03*
Y-90000D03*
Y-65000D03*
Y-25000D03*
Y0D03*
X-502500Y-102500D03*
X-490000Y-90000D03*
X-502500Y-77500D03*
Y-37500D03*
Y-12500D03*
X-490000Y0D03*
X-502500Y12500D03*
X-486421Y-26159D03*
X-477500Y-37500D03*
Y12500D03*
X-465000Y-25000D03*
X-461441Y6559D03*
X-456240Y-82020D03*
X-444440Y-80710D03*
X-454421Y-26959D03*
X-443941Y6559D03*
X-452500Y12500D03*
X-442000Y-29480D03*
X-427500Y12500D03*
X-413500D03*
X-401735Y-181337D03*
Y-185937D03*
X-402559Y-177998D03*
X-403309Y-149480D03*
Y-154080D03*
X-395509Y-149480D03*
Y-154080D03*
X-404134Y-157350D03*
X-402500Y12500D03*
X-394188Y-181074D03*
X-393935Y-185937D03*
X-383661Y-177998D03*
X-393110D03*
X-385237Y-157350D03*
X-394685D03*
X-393847Y-146735D03*
X-393981Y-141950D03*
X-386047Y-142135D03*
Y-146735D03*
X-386500Y-56500D03*
Y-44000D03*
Y-31500D03*
Y-19000D03*
Y-5500D03*
X-390000Y12500D03*
X-367761Y-183080D03*
Y-187680D03*
X-377931Y-184405D03*
Y-192205D03*
X-373331D03*
Y-184405D03*
X-364764Y-177998D03*
X-366339Y-157350D03*
X-365514Y-136650D03*
Y-132050D03*
X-374000Y-56500D03*
Y-44000D03*
Y-31500D03*
Y-19000D03*
X-365000Y12500D03*
X-377500D03*
X-359961Y-183080D03*
Y-187680D03*
X-355315Y-177998D03*
X-347441Y-157350D03*
X-356011Y-152200D03*
X-348211D03*
X-356890Y-157350D03*
X-357714Y-136650D03*
X-356011Y-147600D03*
X-348211D03*
X-357714Y-132050D03*
X-360500Y-87100D03*
X-353700Y-87600D03*
X-361500Y-56500D03*
X-348000Y-57000D03*
X-361500Y-44000D03*
X-348000D03*
Y-31500D03*
X-361500D03*
Y-19000D03*
X-348000D03*
X-352500Y12500D03*
X-341641Y-169660D03*
Y-165060D03*
X-333841D03*
Y-169660D03*
X-345866Y-177998D03*
X-347850Y-87050D03*
X-342400Y-87500D03*
X-336000Y-53000D03*
Y-28000D03*
Y-15500D03*
X-340000Y12500D03*
X-323500Y-65500D03*
X-327500Y12500D03*
X-315000D03*
X-302500D03*
X-285000Y-107400D03*
Y-103100D03*
X-290000Y12500D03*
X-277500D03*
X-254800Y-170650D03*
X-254800Y-175150D03*
X-255672Y-157483D03*
Y-152883D03*
X-256496Y-147990D03*
Y-136730D03*
X-254721Y-129000D03*
X-258732Y-104171D03*
X-255500Y-25500D03*
X-268000Y-13000D03*
X-255500D03*
Y-500D03*
X-268000D03*
X-265000Y12500D03*
X-247872Y-152883D03*
Y-157483D03*
X-247047Y-148090D03*
Y-136730D03*
X-240924Y-123960D03*
X-250321Y-129000D03*
X-240924Y-116160D03*
X-243000Y-40500D03*
Y-25500D03*
Y-13000D03*
Y-500D03*
X-240000Y12500D03*
X-252500D03*
X-226200Y-170650D03*
X-226121Y-175150D03*
X-237598Y-136730D03*
X-228150D03*
Y-148090D03*
X-237598D03*
X-236324Y-123960D03*
Y-116160D03*
X-228932Y-104183D03*
X-230000Y-13500D03*
X-230500Y-500D03*
X-227500Y12500D03*
X-215000D03*
X-202500D03*
X-177500D03*
X-190390Y12740D03*
X-165000Y12500D03*
X-145650Y-100550D03*
X-145100Y-74100D03*
X-152500Y12500D03*
X-138440Y-91390D03*
X-133301Y-86986D03*
X-142559Y-85886D03*
X-129882Y-90706D03*
X-129782Y-75998D03*
X-138640D03*
X-142559Y-70873D03*
X-133701Y-56060D03*
X-129782Y-60885D03*
X-142559Y-56060D03*
X-142130Y-41290D03*
X-139000Y-8500D03*
Y-21000D03*
X-140000Y12500D03*
X-127500D03*
X-126600Y-75410D03*
X-124590Y-41500D03*
X-114000Y-33500D03*
X-126500Y-21000D03*
X-114000Y-8500D03*
Y-21000D03*
X-126500Y-8500D03*
X-115000Y12500D03*
X-99252Y-100849D03*
Y-85886D03*
X-101700Y-73800D03*
X-101500Y-33500D03*
Y-21000D03*
Y-8500D03*
X-102500Y12500D03*
X-95433Y-90706D03*
X-86575D03*
X-90194Y-101049D03*
X-83310Y-75360D03*
X-95333Y-75848D03*
X-86475D03*
Y-60885D03*
X-87700Y-57700D03*
X-95333Y-45922D03*
X-86475D03*
X-89000Y-8500D03*
Y-21000D03*
X-90000Y12500D03*
X-74921Y-171500D03*
X-71500Y-158500D03*
Y-146000D03*
Y-133500D03*
X-71700Y-121000D03*
X-70500Y-108600D03*
X-76500Y-33500D03*
Y-21000D03*
Y-8500D03*
X-77500Y12500D03*
X-65000D03*
X-59500Y-173500D03*
Y-161000D03*
Y-136000D03*
Y-148500D03*
Y-123500D03*
Y-108500D03*
Y-96000D03*
Y-83500D03*
Y-71000D03*
Y-58500D03*
Y-46000D03*
Y-33500D03*
Y-8500D03*
Y-21000D03*
X-54500Y1500D03*
X-52500Y12500D03*
X-42500Y-173500D03*
X-43000Y-158500D03*
Y-146000D03*
X-47000Y-71000D03*
X-34500Y-83500D03*
Y-71000D03*
X-47000Y-83500D03*
X-34500Y-58500D03*
X-47000D03*
Y-46000D03*
X-34500D03*
Y-33500D03*
X-47000D03*
Y-21000D03*
X-34500Y-8500D03*
X-47000D03*
X-34500Y-21000D03*
X-42000Y1500D03*
X-40000Y12500D03*
X-18000Y-173500D03*
Y-158500D03*
X-30500D03*
Y-146000D03*
X-18000D03*
X-21150Y-83600D03*
X-22000Y-71000D03*
Y-58500D03*
Y-46000D03*
Y-33500D03*
Y-21000D03*
Y-8500D03*
X-27500Y12500D03*
X-9500Y-120000D03*
Y-108500D03*
Y-96000D03*
X-9350Y-83500D03*
X-9500Y-71000D03*
Y-58500D03*
Y-46000D03*
Y-33500D03*
Y-8500D03*
Y-21000D03*
X-17000Y1500D03*
X-2500Y12500D03*
X-15000D03*
X3000Y-120000D03*
Y-108500D03*
Y-96000D03*
Y-83500D03*
Y-71000D03*
Y-58500D03*
Y-46000D03*
Y-33500D03*
Y-21000D03*
Y-8500D03*
G54D22*
G01X-1184000Y-502500D02*
Y-512500D01*
G01X-1186683Y-502500D02*
X-1181317D01*
G01X-1176833Y-512500D02*
Y-502500D01*
X-1173917D01*
X-1172983Y-503000D01*
X-1172400Y-503667D01*
X-1172167Y-505000D01*
X-1172400Y-506333D01*
X-1173100Y-507167D01*
X-1173917Y-507667D01*
X-1176833D01*
G01X-1173917D02*
X-1172167Y-512500D01*
G01X-1167917D02*
X-1165000Y-502500D01*
X-1162083Y-512500D01*
G01X-1163133Y-509000D02*
X-1166867D01*
G01X-1155500Y-512500D02*
Y-508000D01*
X-1157833Y-502500D01*
G01X-1153167D02*
X-1155500Y-508000D01*
G01X-1135567Y-507167D02*
X-1135100Y-506667D01*
X-1134750Y-505834D01*
X-1134517Y-504667D01*
X-1134750Y-503667D01*
X-1135217Y-503000D01*
X-1136033Y-502500D01*
X-1139183D01*
Y-512500D01*
X-1135333D01*
X-1134517Y-511833D01*
X-1134050Y-510833D01*
X-1133817Y-509667D01*
X-1134050Y-508500D01*
X-1134750Y-507500D01*
X-1135567Y-507167D01*
X-1139183D01*
G01X-1129917Y-512500D02*
X-1127000Y-502500D01*
X-1124083Y-512500D01*
G01X-1125133Y-509000D02*
X-1128867D01*
G01X-1114933Y-503333D02*
X-1115633Y-502833D01*
X-1116450Y-502500D01*
X-1117383D01*
X-1118433Y-503000D01*
X-1119250Y-503833D01*
X-1119833Y-504833D01*
X-1120300Y-506500D01*
X-1120417Y-508000D01*
X-1120183Y-509500D01*
X-1119833Y-510500D01*
X-1119133Y-511500D01*
X-1118317Y-512167D01*
X-1117500Y-512500D01*
X-1116683D01*
X-1115867Y-512167D01*
X-1115167Y-511667D01*
X-1114583Y-511000D01*
G01X-1110567Y-512500D02*
Y-502500D01*
G01X-1106133D02*
X-1110567Y-508667D01*
G01X-1105433Y-512500D02*
X-1108583Y-505834D01*
G01X-1100833Y-512500D02*
Y-502500D01*
X-1098033D01*
X-1097100Y-503000D01*
X-1096400Y-504167D01*
X-1096167Y-505500D01*
X-1096400Y-506833D01*
X-1096983Y-507833D01*
X-1098033Y-508334D01*
X-1100833D01*
G01X-1091333Y-502500D02*
Y-512500D01*
X-1086667D01*
G01X-1082417D02*
X-1079500Y-502500D01*
X-1076583Y-512500D01*
G01X-1077633Y-509000D02*
X-1081367D01*
G01X-1072683Y-512500D02*
Y-502500D01*
X-1067317Y-512500D01*
Y-502500D01*
G01X-1058167Y-512500D02*
X-1062833D01*
Y-502500D01*
X-1058167D01*
G01X-1060033Y-507333D02*
X-1062833D01*
G01X-1043717Y-512500D02*
Y-502500D01*
X-1039283D01*
G01X-1040917Y-507333D02*
X-1043717D01*
G01X-1034917Y-512500D02*
X-1032000Y-502500D01*
X-1029083Y-512500D01*
G01X-1030133Y-509000D02*
X-1033867D01*
G01X-1021567Y-507167D02*
X-1021100Y-506667D01*
X-1020750Y-505834D01*
X-1020517Y-504667D01*
X-1020750Y-503667D01*
X-1021217Y-503000D01*
X-1022033Y-502500D01*
X-1025183D01*
Y-512500D01*
X-1021333D01*
X-1020517Y-511833D01*
X-1020050Y-510833D01*
X-1019817Y-509667D01*
X-1020050Y-508500D01*
X-1020750Y-507500D01*
X-1021567Y-507167D01*
X-1025183D01*
G01X-1002567D02*
X-1002100Y-506667D01*
X-1001750Y-505834D01*
X-1001517Y-504667D01*
X-1001750Y-503667D01*
X-1002217Y-503000D01*
X-1003033Y-502500D01*
X-1006183D01*
Y-512500D01*
X-1002333D01*
X-1001517Y-511833D01*
X-1001050Y-510833D01*
X-1000817Y-509667D01*
X-1001050Y-508500D01*
X-1001750Y-507500D01*
X-1002567Y-507167D01*
X-1006183D01*
G01X-985083Y-515833D02*
X-986250Y-514167D01*
X-986833Y-512500D01*
Y-505834D01*
X-986250Y-504167D01*
X-985083Y-502500D01*
G01X-975000Y-512500D02*
X-975933Y-512333D01*
X-976750Y-511667D01*
X-977450Y-510667D01*
X-977917Y-509500D01*
X-978150Y-508167D01*
Y-506833D01*
X-977917Y-505500D01*
X-977450Y-504333D01*
X-976750Y-503333D01*
X-975933Y-502667D01*
X-975000Y-502500D01*
X-974067Y-502667D01*
X-973250Y-503333D01*
X-972550Y-504333D01*
X-972083Y-505500D01*
X-971850Y-506833D01*
Y-508167D01*
X-972083Y-509500D01*
X-972550Y-510667D01*
X-973250Y-511667D01*
X-974067Y-512333D01*
X-975000Y-512500D01*
G01X-967950Y-511167D02*
X-967017Y-512000D01*
X-965967Y-512500D01*
X-965033D01*
X-964100Y-512000D01*
X-963400Y-511167D01*
X-963050Y-510000D01*
X-963283Y-508834D01*
X-963867Y-507833D01*
X-964917Y-507167D01*
X-966317Y-506833D01*
X-967133Y-506167D01*
X-967483Y-505000D01*
X-967250Y-503833D01*
X-966667Y-503000D01*
X-965850Y-502500D01*
X-965033D01*
X-964217Y-502833D01*
X-963517Y-503667D01*
G01X-958333Y-512500D02*
Y-502500D01*
X-955533D01*
X-954600Y-503000D01*
X-953900Y-504167D01*
X-953667Y-505500D01*
X-953900Y-506833D01*
X-954483Y-507833D01*
X-955533Y-508334D01*
X-958333D01*
G01X-945917Y-515833D02*
X-944750Y-514167D01*
X-944167Y-512500D01*
Y-505834D01*
X-944750Y-504167D01*
X-945917Y-502500D01*
G01X-902000Y-470000D02*
Y-460000D01*
X-903400Y-462000D01*
G01Y-470000D02*
X-900600D01*
G01X-892500Y-470333D02*
X-892733Y-470167D01*
Y-469833D01*
X-892500Y-469667D01*
X-892267Y-469833D01*
Y-470167D01*
X-892500Y-470333D01*
G01Y-465834D02*
X-892733Y-465667D01*
Y-465333D01*
X-892500Y-465167D01*
X-892267Y-465333D01*
Y-465667D01*
X-892500Y-465834D01*
G01X-883000Y-470000D02*
Y-460000D01*
X-884400Y-462000D01*
G01Y-470000D02*
X-881600D01*
G01X-785060Y-472187D02*
X-784127Y-473020D01*
X-783077Y-473520D01*
X-782143D01*
X-781210Y-473020D01*
X-780510Y-472187D01*
X-780160Y-471020D01*
X-780393Y-469854D01*
X-780977Y-468853D01*
X-782027Y-468187D01*
X-783427Y-467853D01*
X-784243Y-467187D01*
X-784593Y-466020D01*
X-784360Y-464853D01*
X-783777Y-464020D01*
X-782960Y-463520D01*
X-782143D01*
X-781327Y-463853D01*
X-780627Y-464687D01*
G01X-775560Y-473520D02*
Y-463520D01*
G01X-770660D02*
Y-473520D01*
G01Y-468520D02*
X-775560D01*
G01X-766527Y-473520D02*
X-763610Y-463520D01*
X-760693Y-473520D01*
G01X-761743Y-470020D02*
X-765477D01*
G01X-757610Y-463520D02*
X-755977Y-473520D01*
X-754110Y-463520D01*
X-752243Y-473520D01*
X-750610Y-463520D01*
G01X-668067Y-470500D02*
X-667367Y-471667D01*
X-666433Y-472333D01*
X-665383Y-472500D01*
X-664450Y-472333D01*
X-663517Y-471500D01*
X-662933Y-470500D01*
X-662817Y-469500D01*
X-663050Y-468334D01*
X-663867Y-467500D01*
X-664683Y-467167D01*
X-665733D01*
G01X-664683D02*
X-663983Y-466667D01*
X-663400Y-465834D01*
X-663167Y-464833D01*
X-663400Y-463833D01*
X-663983Y-463000D01*
X-665033Y-462500D01*
X-666083Y-462667D01*
X-667133Y-463333D01*
G01X-656000Y-462500D02*
X-656933Y-462833D01*
X-657633Y-463667D01*
X-658100Y-464667D01*
X-658450Y-466000D01*
X-658567Y-467500D01*
X-658450Y-469000D01*
X-658100Y-470333D01*
X-657633Y-471334D01*
X-656933Y-472167D01*
X-656000Y-472500D01*
X-655067Y-472167D01*
X-654367Y-471334D01*
X-653900Y-470333D01*
X-653550Y-469000D01*
X-653433Y-467500D01*
X-653550Y-466000D01*
X-653900Y-464667D01*
X-654367Y-463667D01*
X-655067Y-462833D01*
X-656000Y-462500D01*
G01X-648017Y-469167D02*
X-644983D01*
G01X-639917Y-472500D02*
X-637000Y-462500D01*
X-634083Y-472500D01*
G01X-635133Y-469000D02*
X-638867D01*
G01X-629833Y-472500D02*
Y-462500D01*
X-627033D01*
X-626100Y-463000D01*
X-625400Y-464167D01*
X-625167Y-465500D01*
X-625400Y-466833D01*
X-625983Y-467833D01*
X-627033Y-468334D01*
X-629833D01*
G01X-620333Y-472500D02*
Y-462500D01*
X-617417D01*
X-616483Y-463000D01*
X-615900Y-463667D01*
X-615667Y-465000D01*
X-615900Y-466333D01*
X-616600Y-467167D01*
X-617417Y-467667D01*
X-620333D01*
G01X-617417D02*
X-615667Y-472500D01*
G01X-610017Y-469167D02*
X-606983D01*
G01X-599000Y-472500D02*
Y-462500D01*
X-600400Y-464500D01*
G01Y-472500D02*
X-597600D01*
G01X-588100D02*
Y-462500D01*
X-592417Y-469667D01*
X-586583D01*
G54D13*
X-1649000Y-97878D03*
X-1327756Y-175039D03*
Y-167165D03*
Y-159291D03*
Y-143543D03*
Y-135669D03*
Y-127795D03*
X-1319882Y-175039D03*
Y-167165D03*
Y-159291D03*
Y-143543D03*
Y-135669D03*
Y-127795D03*
X-793728Y-138228D03*
X-457677Y-175039D03*
Y-167165D03*
Y-159291D03*
Y-143543D03*
Y-135669D03*
Y-127795D03*
X-449803Y-175039D03*
Y-167165D03*
Y-159291D03*
Y-143543D03*
Y-135669D03*
Y-127795D03*
G54D23*
G01X-1174900Y-473500D02*
X-1171300Y-466100D01*
X-1171800Y-465700D01*
X-1175900Y-473200D01*
X-1176200Y-471200D01*
X-1172500Y-465400D01*
X-1175700Y-471300D01*
X-1176500Y-469800D01*
X-1172900Y-464900D01*
X-1173600Y-451800D01*
X-1173700Y-449900D01*
X-1182100D01*
X-1187400Y-473000D01*
X-1182400D01*
X-1177800Y-456000D01*
X-1177000Y-455900D01*
X-1176100Y-468500D01*
X-1173700Y-464500D01*
X-1174600Y-450800D01*
X-1181500Y-450900D01*
X-1186400Y-472100D01*
X-1183100D01*
X-1178300Y-454800D01*
X-1176600Y-455000D01*
X-1175500Y-466300D01*
X-1174600Y-464300D01*
X-1175400Y-451700D01*
X-1181000Y-451800D01*
X-1185300Y-471300D01*
X-1183800Y-471400D01*
X-1179000Y-454300D01*
X-1176200D01*
X-1175200Y-462200D01*
X-1176200Y-452500D01*
X-1180500Y-452800D01*
X-1184300Y-470600D01*
X-1179700Y-453400D01*
X-1176800D01*
G01X-1182820Y-448900D02*
X-1188360Y-473900D01*
X-1181580D01*
X-1177300Y-456700D01*
X-1176920Y-473900D01*
X-1172260D01*
X-1163400Y-456920D01*
X-1167240Y-473900D01*
X-1160380D01*
X-1154840Y-448900D01*
X-1164540D01*
X-1172540Y-464820D01*
X-1172880Y-448900D01*
X-1182820D01*
G01X-1155800Y-449500D02*
X-1161100Y-472900D01*
X-1166100Y-473000D01*
X-1166000Y-471900D01*
X-1161800Y-472100D01*
X-1161300Y-471000D01*
X-1165900Y-471100D01*
X-1165700Y-470000D01*
X-1161300D01*
X-1160800Y-469200D01*
X-1165300Y-469100D01*
X-1165200Y-468100D01*
X-1160700D01*
X-1160400Y-467100D01*
X-1165100Y-467200D01*
X-1164900Y-466300D01*
X-1160300Y-466200D01*
X-1160000Y-465200D01*
X-1164700Y-465300D01*
X-1164400Y-464200D01*
X-1159700Y-464300D01*
X-1159300Y-463100D01*
X-1164700Y-463500D01*
X-1164000Y-462500D01*
X-1159500Y-462600D01*
X-1159000Y-461700D01*
X-1163900D01*
X-1163600Y-460600D01*
X-1159100Y-460800D01*
X-1158800Y-459900D01*
X-1163200D01*
X-1163100Y-459200D01*
X-1158800D01*
X-1158300Y-458500D01*
X-1163000Y-458400D01*
X-1162900Y-457800D01*
X-1158400Y-457900D01*
X-1158200Y-457200D01*
X-1162500Y-457000D01*
X-1163100Y-456500D01*
X-1157800D01*
X-1157500Y-455500D01*
X-1156600Y-449800D01*
X-1164000D01*
X-1164500Y-450700D01*
X-1157600D01*
X-1157800Y-451700D01*
X-1165000Y-451600D01*
X-1165400Y-452400D01*
X-1157900Y-452500D01*
X-1157800Y-453500D01*
X-1165900Y-453200D01*
X-1166200Y-453900D01*
X-1158000Y-454300D01*
X-1158300Y-455300D01*
X-1166600Y-454800D01*
X-1158900Y-455900D01*
X-1167000Y-455600D01*
X-1163500Y-456400D01*
X-1167300Y-456300D01*
X-1171700Y-465200D01*
X-1169200Y-466400D01*
X-1164500Y-457200D01*
X-1166900Y-457100D01*
X-1170600Y-465200D01*
X-1169500Y-465500D01*
X-1166000Y-457800D01*
G01X-1170300Y-466300D02*
X-1174000Y-473600D01*
G01X-1169500Y-466900D02*
X-1172800Y-473000D01*
G01X-1152800Y-456400D02*
X-1156600Y-473100D01*
X-1152200Y-473000D01*
X-1148300Y-456600D01*
X-1149500D01*
X-1152900Y-472000D01*
X-1155600Y-472300D01*
X-1152100Y-456500D01*
X-1150400Y-456400D01*
X-1153600Y-471200D01*
X-1154500Y-471400D01*
X-1151400Y-457200D01*
G01X-1153420Y-455700D02*
X-1157540Y-473900D01*
X-1151380D01*
X-1147440Y-455700D01*
X-1153420D01*
G01X-1151600Y-450100D02*
X-1146700Y-450000D01*
X-1147000Y-451000D01*
X-1151700D01*
G01X-1152020Y-448900D02*
X-1152660Y-451900D01*
X-1146380D01*
X-1145740Y-448900D01*
X-1152020D01*
G01X-1129400Y-468900D02*
X-1131800Y-471900D01*
X-1136500Y-473700D01*
X-1142100Y-473600D01*
X-1144600Y-472300D01*
X-1145800Y-471000D01*
X-1146400Y-469500D01*
X-1146700Y-467600D01*
X-1146500Y-464600D01*
X-1145400Y-461200D01*
X-1143500Y-459100D01*
X-1140200Y-456900D01*
X-1136100Y-456200D01*
X-1132300Y-456400D01*
X-1129400Y-457900D01*
X-1127500Y-460900D01*
X-1132500Y-461000D01*
X-1133400Y-459200D01*
X-1135100Y-458100D01*
X-1136800Y-458000D01*
X-1138600Y-458900D01*
X-1140300Y-460700D01*
X-1141800Y-463600D01*
X-1142400Y-466600D01*
X-1141500Y-470400D01*
X-1140200Y-471500D01*
X-1138300Y-471600D01*
X-1136300Y-471400D01*
X-1134500Y-469100D01*
X-1130300Y-469000D01*
X-1132500Y-471200D01*
X-1134900Y-472000D01*
X-1137200Y-472800D01*
X-1142300Y-472700D01*
X-1144900Y-470600D01*
X-1145800Y-467400D01*
X-1145500Y-465100D01*
X-1144700Y-462000D01*
X-1143300Y-460200D01*
X-1139800Y-457700D01*
X-1135400Y-457000D01*
X-1131300Y-457600D01*
X-1128800Y-460100D01*
X-1132100D01*
X-1134300Y-457900D01*
X-1130100Y-458800D01*
X-1129500Y-459400D01*
X-1132600Y-459000D01*
G01X-1133300Y-461900D02*
Y-461420D01*
X-1133640Y-460240D01*
X-1134300Y-459200D01*
X-1135200Y-458900D01*
X-1136580D01*
X-1138060Y-459820D01*
X-1139360Y-461000D01*
X-1140240Y-462220D01*
X-1140880Y-463920D01*
X-1141300Y-465380D01*
X-1141500Y-467060D01*
Y-468020D01*
X-1141020Y-469220D01*
X-1139780Y-470700D01*
X-1137160D01*
X-1135840Y-469500D01*
X-1134980Y-468200D01*
X-1134940Y-468100D01*
X-1128180D01*
X-1128240Y-468240D01*
X-1128840Y-469340D01*
X-1129020Y-469800D01*
X-1129740Y-470700D01*
X-1130500Y-471460D01*
X-1131660Y-472420D01*
X-1132820Y-473200D01*
X-1133740Y-473740D01*
X-1136380Y-474500D01*
X-1141640D01*
X-1142540Y-474320D01*
X-1144220Y-473760D01*
X-1144900Y-473240D01*
X-1146240Y-471900D01*
X-1146780Y-471180D01*
X-1146940Y-470880D01*
X-1147320Y-469660D01*
X-1147500Y-468640D01*
Y-464780D01*
X-1146940Y-462540D01*
X-1146380Y-461580D01*
X-1145980Y-460780D01*
X-1145420Y-459880D01*
X-1143700Y-458140D01*
X-1142740Y-457380D01*
X-1142000Y-456820D01*
X-1140240Y-456040D01*
X-1139500Y-455660D01*
X-1138800Y-455480D01*
X-1137260Y-455300D01*
X-1134320D01*
X-1132020Y-455500D01*
X-1130940Y-455860D01*
X-1130580Y-456020D01*
X-1129260Y-456780D01*
X-1128940Y-457100D01*
X-1127820Y-458420D01*
X-1127060Y-460300D01*
X-1126900Y-460800D01*
Y-461900D01*
X-1133300D01*
G01X-1137900Y-458000D02*
X-1140300Y-459100D01*
X-1142500Y-460900D01*
X-1143900Y-462600D01*
X-1144800Y-467600D01*
X-1144200Y-470000D01*
X-1141000Y-472300D01*
X-1136400Y-472200D01*
X-1131600Y-469600D01*
X-1135400Y-470400D01*
X-1141100Y-471400D01*
X-1142100Y-470700D01*
X-1142700Y-469000D01*
X-1143100Y-467100D01*
X-1142700Y-464100D01*
X-1140500Y-459900D01*
X-1143400Y-463700D01*
X-1143600Y-465700D01*
X-1143900Y-467700D01*
X-1143000Y-469900D01*
G01X-1113500Y-459200D02*
X-1123500Y-459300D01*
X-1123700Y-460100D01*
X-1114300Y-460000D01*
X-1116500Y-460800D01*
X-1124200Y-461000D01*
X-1124400Y-461900D01*
X-1117600Y-461800D01*
X-1118800Y-462800D01*
X-1124500Y-462700D01*
X-1124600Y-463600D01*
X-1119300Y-463700D01*
X-1120100Y-464800D01*
X-1125000Y-464600D01*
Y-465500D01*
X-1120600Y-465700D01*
X-1120800Y-466700D01*
X-1125300Y-466500D01*
X-1125500Y-467400D01*
X-1121000Y-467600D01*
X-1121200Y-468700D01*
X-1125600Y-468400D01*
X-1125900Y-469100D01*
X-1121500Y-469500D01*
X-1121700Y-470700D01*
X-1126100Y-470000D01*
X-1126200Y-470700D01*
X-1121900Y-471200D01*
X-1122100Y-472000D01*
X-1126300Y-471700D01*
X-1126700Y-472300D01*
X-1122100Y-472700D01*
X-1122200Y-473100D01*
X-1126800Y-473200D01*
G01X-1114060Y-460760D02*
X-1114840Y-460920D01*
X-1115740Y-461140D01*
X-1116880Y-461820D01*
X-1117700Y-462640D01*
X-1118620Y-463340D01*
X-1118840Y-464020D01*
X-1119440Y-464820D01*
X-1119660Y-465480D01*
X-1120060Y-466280D01*
X-1120280Y-466960D01*
X-1120480Y-468360D01*
X-1120680Y-468940D01*
X-1120880Y-469940D01*
X-1121080Y-470540D01*
X-1121700Y-472980D01*
X-1121820Y-473900D01*
X-1127640D01*
X-1126920Y-471060D01*
X-1126720Y-470440D01*
X-1126500Y-468800D01*
X-1126320Y-467860D01*
X-1126120Y-467260D01*
X-1125920Y-466260D01*
X-1125720Y-465660D01*
X-1125300Y-464000D01*
X-1125120Y-462220D01*
X-1124920Y-461660D01*
X-1124720Y-460660D01*
X-1124520Y-460060D01*
X-1123720Y-456800D01*
X-1123580Y-455700D01*
X-1117880D01*
X-1118100Y-456160D01*
Y-458740D01*
X-1116500Y-457160D01*
X-1115780Y-456620D01*
X-1114680Y-456060D01*
X-1113560Y-455680D01*
X-1112460Y-455500D01*
X-1111720D01*
X-1112460Y-458440D01*
X-1114060Y-460760D01*
G01X-1123100Y-456500D02*
X-1118900Y-456600D01*
X-1118800Y-457600D01*
X-1123100Y-457500D01*
X-1123300Y-458500D01*
X-1113100Y-458400D01*
X-1112600Y-456400D01*
X-1116100Y-457600D01*
X-1113500D01*
G01X-1105100Y-471100D02*
X-1104060D01*
X-1103780Y-470820D01*
X-1103200Y-470640D01*
X-1102080Y-469740D01*
X-1100800Y-468240D01*
X-1100380Y-467400D01*
X-1100180Y-467100D01*
X-1099960Y-466660D01*
X-1099540Y-465720D01*
X-1099320Y-465060D01*
X-1099100Y-464180D01*
Y-461220D01*
X-1099360Y-460200D01*
X-1099660Y-459900D01*
X-1100700Y-458640D01*
X-1101220Y-458300D01*
X-1103340D01*
X-1103700Y-458640D01*
X-1105300Y-459840D01*
X-1105760Y-460320D01*
X-1106180Y-460940D01*
X-1107060Y-462020D01*
X-1107260Y-462880D01*
X-1107660Y-463660D01*
X-1108100Y-465000D01*
Y-468640D01*
X-1107620Y-469600D01*
X-1107140Y-470340D01*
X-1105980Y-471100D01*
X-1105100D01*
G01X-1112540Y-460460D02*
X-1110680Y-458140D01*
X-1109940Y-457580D01*
X-1109000Y-456840D01*
X-1108480Y-456660D01*
X-1107940Y-456400D01*
X-1107740Y-456200D01*
X-1107480Y-456060D01*
X-1106880Y-455860D01*
X-1106480Y-455660D01*
X-1105960Y-455480D01*
X-1104600Y-455300D01*
X-1103440Y-455100D01*
X-1100940D01*
X-1098240Y-455480D01*
X-1097720Y-455660D01*
X-1097020Y-456020D01*
X-1096180Y-456640D01*
X-1095620Y-456820D01*
X-1095540Y-456900D01*
X-1094200Y-458440D01*
X-1093660Y-459520D01*
X-1093460Y-460100D01*
X-1093100Y-461020D01*
Y-464400D01*
X-1093420Y-465360D01*
X-1094300Y-465520D01*
X-1094720Y-465740D01*
X-1095320Y-465940D01*
X-1096120Y-466340D01*
X-1096720Y-466540D01*
X-1097100Y-466720D01*
X-1098100Y-466920D01*
X-1098520Y-467140D01*
X-1099160Y-467360D01*
X-1101180Y-468700D01*
X-1094660D01*
X-1095220Y-469800D01*
X-1095560Y-470320D01*
X-1097480Y-472220D01*
X-1099940Y-473740D01*
X-1102580Y-474500D01*
X-1108800D01*
X-1109300Y-474340D01*
X-1111220Y-473560D01*
X-1111720Y-473240D01*
X-1113240Y-471720D01*
X-1113560Y-471240D01*
X-1113760Y-470660D01*
X-1114140Y-469980D01*
X-1114320Y-469120D01*
X-1114500Y-468680D01*
Y-464980D01*
X-1114320Y-464260D01*
X-1114140Y-463720D01*
X-1113940Y-463320D01*
X-1113720Y-462660D01*
X-1113560Y-462000D01*
X-1111880Y-460320D01*
X-1112540Y-460460D01*
G01X-1099300Y-466400D02*
X-1093800Y-464400D01*
X-1093900Y-461100D01*
X-1094800Y-459000D01*
X-1096800Y-457300D01*
X-1100000Y-456100D01*
X-1102800Y-455900D01*
X-1106300Y-456300D01*
X-1109600Y-458100D01*
X-1111400Y-460500D01*
X-1112900Y-462600D01*
X-1113600Y-465600D01*
X-1113500Y-469100D01*
X-1112100Y-471900D01*
X-1109600Y-473300D01*
X-1105700Y-473800D01*
X-1101000Y-473400D01*
X-1098200Y-471800D01*
X-1096600Y-470100D01*
X-1096000Y-469500D01*
X-1100800Y-469700D01*
X-1102300Y-471100D01*
X-1097900Y-470400D01*
X-1100300Y-471800D01*
X-1103200Y-471400D01*
X-1100600Y-472600D01*
X-1103000D01*
X-1103700Y-471900D01*
X-1103400Y-473000D01*
X-1104600Y-471900D01*
X-1106200D01*
X-1104100Y-473100D01*
X-1107200Y-472700D01*
X-1110100Y-472100D01*
X-1111500Y-470900D01*
X-1112600Y-468600D01*
X-1112700Y-466000D01*
X-1112400Y-463700D01*
X-1111400Y-461600D01*
X-1109600Y-459500D01*
X-1108100Y-458200D01*
X-1105900Y-457200D01*
X-1102200Y-456700D01*
X-1099600Y-457300D01*
X-1097000Y-458400D01*
X-1095500Y-459500D01*
X-1094600Y-461900D01*
X-1094500Y-463900D01*
X-1098800Y-465200D01*
X-1098600Y-464000D01*
X-1095100Y-463100D01*
X-1095300Y-462000D01*
X-1098500Y-463000D01*
X-1098600Y-461700D01*
X-1095600Y-461300D01*
X-1095900Y-460200D01*
X-1098400Y-460700D01*
X-1098900Y-459900D01*
X-1096600Y-459400D01*
X-1097100Y-458900D01*
X-1099400Y-459000D01*
X-1098800Y-458500D01*
X-1100600Y-458000D01*
X-1102400Y-457400D01*
X-1104200Y-457500D01*
X-1106200Y-458100D01*
X-1107900Y-459000D01*
X-1110500Y-462200D01*
X-1111800Y-464800D01*
Y-467700D01*
X-1110700Y-470300D01*
X-1108700Y-472000D01*
X-1106600Y-471900D01*
X-1107900Y-470300D01*
X-1108900Y-468700D01*
Y-465500D01*
X-1107900Y-462300D01*
X-1106500Y-459900D01*
X-1104100Y-458200D01*
X-1108000Y-460000D01*
X-1108100Y-461500D01*
X-1108700Y-461200D01*
X-1110300Y-463600D01*
X-1111000Y-466000D01*
X-1110700Y-468100D01*
X-1109500Y-470600D01*
X-1107700Y-471400D01*
X-1109300Y-469100D01*
X-1109800Y-467600D01*
X-1108600Y-462200D01*
X-1110400Y-466800D01*
G01X-1113600Y-460900D02*
X-1112100Y-459000D01*
G01X-1093100Y-469400D02*
X-1087900Y-469700D01*
X-1086500Y-471400D01*
X-1083400Y-472300D01*
X-1081000Y-472000D01*
X-1079300Y-470600D01*
X-1079000Y-468900D01*
X-1079500Y-467700D01*
X-1080300Y-466600D01*
X-1081800Y-466000D01*
X-1083300Y-465500D01*
X-1085300Y-465000D01*
X-1087900Y-464000D01*
X-1089100Y-463200D01*
X-1089800Y-461000D01*
X-1089500Y-459000D01*
X-1088600Y-457700D01*
X-1086500Y-456700D01*
X-1084600Y-456100D01*
X-1081900Y-455900D01*
X-1079900Y-455800D01*
X-1076900Y-456300D01*
X-1075000Y-457000D01*
X-1073700Y-458000D01*
X-1073300Y-459400D01*
X-1077600Y-459500D01*
X-1078100Y-458800D01*
X-1074300Y-458500D01*
X-1074600Y-457800D01*
X-1078200Y-458200D01*
X-1076000Y-457400D01*
X-1079100Y-457700D01*
X-1077100Y-456900D01*
X-1080100Y-457300D01*
X-1079200Y-456600D01*
X-1083100Y-456800D01*
X-1080600Y-457300D01*
X-1083400Y-457700D01*
X-1083600Y-457000D01*
X-1087900Y-458400D01*
X-1084000Y-458100D01*
X-1088600Y-459100D01*
X-1088800Y-461500D01*
X-1087700Y-463600D01*
X-1084400Y-464300D01*
X-1081200Y-465400D01*
X-1078800Y-467300D01*
X-1078300Y-470500D01*
X-1079900Y-472600D01*
X-1083500Y-473300D01*
X-1085600Y-472600D01*
X-1088800Y-470500D01*
X-1092600Y-470200D01*
X-1092100Y-471800D01*
X-1091700Y-471300D01*
X-1089300Y-471500D01*
X-1091300Y-472300D01*
X-1088700Y-471600D01*
X-1084000Y-473500D01*
X-1089100D01*
X-1091000Y-472900D01*
X-1087200Y-472800D01*
X-1082700Y-473700D01*
X-1079000Y-473600D01*
X-1076500Y-472300D01*
X-1074700Y-470600D01*
X-1074300Y-467300D01*
X-1074800Y-465300D01*
X-1078800Y-463600D01*
X-1081600Y-462900D01*
X-1083400Y-462500D01*
X-1084800Y-461500D01*
X-1085000Y-458900D01*
X-1088100Y-459800D01*
X-1087200Y-462700D01*
X-1085000Y-463400D01*
X-1082000Y-464100D01*
X-1079600Y-465100D01*
X-1078200Y-466500D01*
X-1077700Y-468500D01*
X-1077500Y-470100D01*
X-1079200Y-472800D01*
X-1076800Y-471400D01*
X-1075300Y-470000D01*
X-1077300Y-470900D01*
X-1075000Y-468800D01*
X-1075200Y-466100D01*
X-1082700Y-462700D01*
X-1084200Y-462900D01*
X-1086600Y-461800D01*
X-1087200Y-460300D01*
X-1085800Y-459800D01*
X-1086600Y-461000D01*
X-1085300Y-460400D01*
X-1085600Y-461400D01*
X-1076700Y-466500D01*
X-1075900Y-467100D01*
X-1075700Y-468400D01*
X-1076800Y-469500D01*
X-1077800Y-466200D01*
X-1075900Y-468800D01*
G01X-1093780Y-468700D02*
X-1087100D01*
Y-469740D01*
X-1086800Y-470060D01*
X-1086520Y-470600D01*
X-1085820Y-470820D01*
X-1085660Y-471000D01*
X-1085120Y-471260D01*
X-1084400Y-471500D01*
X-1082360D01*
X-1080540Y-470600D01*
X-1080100Y-470140D01*
Y-469780D01*
X-1079840Y-469380D01*
X-1080380Y-467740D01*
X-1081440Y-466940D01*
X-1082560Y-466720D01*
X-1085740Y-465920D01*
X-1086940Y-465520D01*
X-1087600Y-465360D01*
X-1087740Y-465200D01*
X-1088540Y-464800D01*
X-1089140Y-464200D01*
X-1089540Y-464000D01*
X-1089800Y-463740D01*
X-1090000Y-463340D01*
X-1090180Y-463180D01*
X-1090500Y-462200D01*
Y-459800D01*
X-1090320Y-459260D01*
X-1090140Y-458500D01*
X-1090000Y-458260D01*
X-1089000Y-457260D01*
X-1088860Y-456940D01*
X-1085920Y-455480D01*
X-1083620Y-455100D01*
X-1082060Y-454900D01*
X-1080520D01*
X-1078580Y-455100D01*
X-1076240Y-455480D01*
X-1075120Y-455860D01*
X-1074800Y-456020D01*
X-1073680Y-456760D01*
X-1073160Y-457300D01*
X-1072620Y-458020D01*
X-1072500Y-458240D01*
Y-460300D01*
X-1078500D01*
Y-459200D01*
X-1079580Y-458380D01*
X-1080160Y-458100D01*
X-1082380D01*
X-1083280Y-458360D01*
X-1084020Y-458940D01*
X-1084340Y-459900D01*
X-1084060Y-460720D01*
X-1083740Y-461340D01*
X-1081860Y-462280D01*
X-1079400Y-462500D01*
X-1078660Y-462680D01*
X-1078100Y-462860D01*
X-1076500Y-463460D01*
X-1075320Y-463860D01*
X-1075060Y-464000D01*
X-1073820Y-465220D01*
X-1073480Y-466260D01*
X-1073300Y-467160D01*
Y-468420D01*
X-1073860Y-470700D01*
X-1074000Y-470960D01*
X-1075140Y-472300D01*
X-1075280Y-472440D01*
X-1076600Y-473380D01*
X-1077320Y-473740D01*
X-1079600Y-474500D01*
X-1088240D01*
X-1089160Y-474320D01*
X-1089920Y-474120D01*
X-1090860Y-473760D01*
X-1091560Y-473400D01*
X-1092700Y-472460D01*
X-1093180Y-471980D01*
X-1093340Y-471480D01*
X-1093520Y-471100D01*
X-1093700Y-470320D01*
X-1093780Y-468700D01*
G01X-1095100D02*
X-1092800D01*
G01X-1058300Y-469400D02*
X-1055400Y-467100D01*
X-1053900Y-463700D01*
X-1054400Y-461200D01*
X-1055900Y-459900D01*
X-1054800Y-463500D01*
X-1055400Y-463600D01*
X-1054600Y-464500D01*
X-1055700D01*
X-1055400Y-465300D01*
X-1056200Y-466800D01*
G01X-1059300Y-457700D02*
X-1059100Y-455600D01*
X-1055200Y-456300D01*
X-1052700Y-457900D01*
X-1051100Y-460800D01*
X-1050900Y-465200D01*
X-1052900Y-469400D01*
X-1055300Y-471900D01*
X-1059000Y-473500D01*
X-1066000D01*
X-1068000Y-471900D01*
X-1070200Y-468700D01*
X-1070600Y-464500D01*
X-1069000Y-460500D01*
X-1066000Y-457500D01*
X-1063000Y-456500D01*
X-1059200Y-456000D01*
X-1053000Y-458500D01*
X-1052000Y-461500D01*
Y-465700D01*
X-1053400Y-468600D01*
X-1055700Y-471000D01*
X-1058900Y-472600D01*
X-1063700Y-473000D01*
X-1065900Y-473600D01*
X-1068300Y-472900D01*
X-1070600Y-469300D01*
X-1065100Y-472600D01*
X-1060800Y-472200D01*
X-1057200Y-470700D01*
X-1055200Y-469100D01*
X-1053300Y-466500D01*
X-1052500Y-463400D01*
X-1052900Y-460100D01*
X-1057000Y-457400D01*
X-1058700Y-457200D01*
X-1057000Y-458500D01*
X-1055100Y-459800D01*
X-1053800Y-460900D01*
X-1053400Y-463100D01*
X-1053600Y-465600D01*
X-1054800Y-467500D01*
X-1056400Y-469200D01*
X-1058500Y-470200D01*
X-1060200Y-470700D01*
X-1061500Y-471400D01*
X-1063300Y-471600D01*
X-1065400Y-471500D01*
X-1069000Y-469300D01*
X-1069600Y-466400D01*
X-1069700Y-463700D01*
X-1068600Y-461200D01*
X-1066700Y-459200D01*
X-1063900Y-457600D01*
X-1061100Y-457000D01*
X-1059600D01*
X-1060200Y-457500D01*
X-1063300Y-458000D01*
X-1065300Y-459500D01*
X-1066900Y-460600D01*
X-1067900Y-462100D01*
X-1068800Y-464300D01*
X-1068700Y-466900D01*
X-1068200Y-469100D01*
X-1066900Y-470200D01*
X-1064300Y-470900D01*
X-1065700Y-469300D01*
X-1065800Y-465900D01*
X-1065300Y-462900D01*
X-1061200Y-458200D01*
X-1063600Y-458900D01*
X-1066400Y-461300D01*
X-1067800Y-464200D01*
Y-467200D01*
X-1067400Y-469300D01*
X-1066300Y-469700D01*
X-1067100Y-466400D01*
X-1066600Y-463400D01*
X-1064700Y-460000D01*
X-1062600Y-458800D01*
X-1065300Y-461700D01*
X-1066700Y-467400D01*
G01X-1060840Y-455100D02*
X-1057160D01*
X-1055260Y-455480D01*
X-1054740Y-455640D01*
X-1053380Y-456420D01*
X-1052660Y-456800D01*
X-1052020Y-457420D01*
X-1051820Y-458020D01*
X-1051200Y-458660D01*
X-1051000Y-459060D01*
X-1050840Y-459200D01*
X-1050700Y-459780D01*
Y-460140D01*
X-1050400Y-460460D01*
X-1050280Y-460680D01*
X-1050100Y-461740D01*
Y-464240D01*
X-1050280Y-465160D01*
X-1050480Y-465980D01*
X-1050680Y-467120D01*
X-1051220Y-468180D01*
X-1051840Y-469020D01*
X-1052040Y-469600D01*
X-1052740Y-470500D01*
X-1054480Y-472240D01*
X-1055000Y-472580D01*
X-1055420Y-472780D01*
X-1056220Y-473380D01*
X-1056920Y-473740D01*
X-1059380Y-474500D01*
X-1065600D01*
X-1067860Y-473740D01*
X-1068160Y-473600D01*
X-1069500Y-472460D01*
X-1069820Y-472120D01*
X-1070380Y-471200D01*
X-1071140Y-469860D01*
X-1071300Y-469400D01*
Y-464580D01*
X-1071120Y-463880D01*
X-1070740Y-462900D01*
X-1070540Y-462320D01*
X-1069980Y-461000D01*
X-1068840Y-459500D01*
X-1066900Y-457560D01*
X-1066180Y-457020D01*
X-1065400Y-456620D01*
X-1064440Y-456040D01*
X-1063500Y-455660D01*
X-1062940Y-455480D01*
X-1060840Y-455100D01*
G01X-1057800Y-458580D02*
X-1057000Y-459120D01*
X-1056760Y-459840D01*
X-1056340Y-460460D01*
X-1056100Y-461640D01*
Y-463760D01*
X-1056320Y-464860D01*
X-1056720Y-466060D01*
X-1056940Y-466920D01*
X-1057200Y-467460D01*
X-1057640Y-467880D01*
X-1058040Y-468480D01*
X-1059960Y-470420D01*
X-1061020Y-470840D01*
X-1061420Y-471100D01*
X-1062720D01*
X-1063340Y-470840D01*
X-1063860Y-470600D01*
X-1064360Y-470080D01*
X-1064820Y-469400D01*
X-1065100Y-468840D01*
Y-464920D01*
X-1064880Y-464120D01*
X-1064420Y-462780D01*
X-1064160Y-462520D01*
X-1063620Y-461700D01*
X-1063200Y-460840D01*
X-1062500Y-460140D01*
X-1062120Y-459860D01*
X-1061720Y-459360D01*
X-1060600Y-458580D01*
X-1060040Y-458300D01*
X-1058360D01*
X-1057800Y-458580D01*
G01X-1040300Y-459100D02*
X-1041400Y-464800D01*
G01X-1044800Y-458200D02*
X-1041400D01*
X-1044300Y-472700D01*
X-1047400Y-472300D01*
X-1044100Y-458800D01*
X-1042400Y-459100D01*
X-1045100Y-471900D01*
X-1046500D01*
X-1043400Y-459700D01*
X-1045600Y-471500D01*
G01X-1036600Y-449900D02*
X-1036800Y-451300D01*
X-1038600Y-452400D01*
X-1039800Y-456100D01*
X-1033700Y-456500D01*
X-1032300Y-452100D01*
X-1028400Y-452000D01*
X-1028900Y-455400D01*
X-1027200Y-456600D01*
X-1025900Y-456800D01*
X-1026200Y-458200D01*
X-1030000Y-458400D01*
X-1031800Y-468900D01*
X-1030400Y-471700D01*
X-1029400D01*
X-1029600Y-473300D01*
X-1033100Y-473400D01*
X-1036100Y-472800D01*
X-1036200Y-470500D01*
X-1035900Y-467100D01*
X-1034400Y-461400D01*
X-1033800Y-458800D01*
X-1033500Y-458400D01*
X-1035000Y-458200D01*
X-1039600D01*
X-1040800Y-458300D01*
X-1043600Y-473200D01*
X-1048000Y-473000D01*
X-1045100Y-459400D01*
X-1044900Y-458400D01*
X-1048700D01*
X-1048100Y-456600D01*
X-1044900Y-456400D01*
X-1045200Y-457700D01*
X-1047600Y-457500D01*
X-1026500D01*
G01X-1049580Y-459100D02*
X-1048740Y-455700D01*
X-1044900D01*
Y-454780D01*
X-1044720Y-454060D01*
X-1044340Y-452920D01*
X-1043940Y-452120D01*
X-1043740Y-451520D01*
X-1043600Y-451260D01*
X-1042340Y-450000D01*
X-1042080Y-449860D01*
X-1040580Y-449480D01*
X-1039440Y-449300D01*
X-1036140D01*
X-1035440Y-449400D01*
X-1035480Y-449540D01*
X-1035680Y-450360D01*
X-1035880Y-451280D01*
X-1036000Y-451900D01*
X-1036740D01*
X-1037060Y-452200D01*
X-1037860Y-452600D01*
X-1038220Y-452980D01*
X-1038480Y-453740D01*
X-1038960Y-455700D01*
X-1034020D01*
X-1033720Y-455080D01*
X-1033500Y-453400D01*
X-1032940Y-451100D01*
X-1027260D01*
X-1027280Y-451180D01*
X-1027480Y-452780D01*
X-1027860Y-454280D01*
X-1028100Y-454760D01*
Y-455700D01*
X-1024800D01*
X-1024880Y-455940D01*
X-1025080Y-456940D01*
X-1025280Y-457540D01*
X-1025480Y-458560D01*
X-1025620Y-459100D01*
X-1029100D01*
Y-460000D01*
X-1029280Y-460540D01*
X-1029480Y-461540D01*
X-1029680Y-462140D01*
X-1029880Y-462960D01*
X-1030100Y-464000D01*
X-1030280Y-465560D01*
X-1030480Y-466140D01*
X-1030680Y-467140D01*
X-1030880Y-467740D01*
X-1031040Y-468400D01*
X-1031300Y-468660D01*
Y-469800D01*
X-1030300Y-470560D01*
X-1029940Y-470900D01*
X-1028220D01*
X-1028680Y-472780D01*
X-1028880Y-474120D01*
Y-474140D01*
X-1030720Y-474300D01*
X-1032860D01*
X-1034380Y-474120D01*
X-1035860Y-473740D01*
X-1036640Y-473280D01*
X-1036960Y-472660D01*
X-1037100Y-472280D01*
Y-470160D01*
X-1036920Y-469260D01*
X-1036700Y-468640D01*
X-1036500Y-466840D01*
X-1036320Y-466260D01*
X-1036120Y-465260D01*
X-1035920Y-464660D01*
X-1035720Y-463660D01*
X-1035520Y-463060D01*
X-1035320Y-462060D01*
X-1035120Y-461440D01*
X-1034820Y-459100D01*
X-1039900D01*
Y-460220D01*
X-1040280Y-461780D01*
X-1040480Y-463380D01*
X-1041280Y-466540D01*
X-1041480Y-467140D01*
X-1041700Y-468200D01*
X-1041880Y-469760D01*
X-1042080Y-470340D01*
X-1042280Y-471360D01*
X-1042480Y-472140D01*
X-1042680Y-472740D01*
X-1042880Y-473740D01*
X-1042940Y-473900D01*
X-1049140D01*
X-1048300Y-470620D01*
X-1048100Y-469020D01*
X-1047920Y-468260D01*
X-1047720Y-467660D01*
X-1047520Y-466660D01*
X-1047320Y-466060D01*
X-1047120Y-465060D01*
X-1046920Y-464460D01*
X-1046700Y-463400D01*
X-1046500Y-462020D01*
X-1046140Y-460500D01*
X-1045900Y-460040D01*
Y-459100D01*
X-1049580D01*
G01X-1038400Y-451100D02*
X-1040600Y-455800D01*
X-1043300D01*
X-1041400Y-451300D01*
X-1038900Y-451000D01*
X-1041200Y-455000D01*
X-1042000Y-455100D01*
X-1040500Y-452000D01*
G01X-1037500Y-449800D02*
X-1037800Y-451000D01*
X-1038500Y-450100D01*
X-1042000Y-450700D01*
X-1043100Y-452300D01*
X-1044100Y-455100D01*
X-1044200Y-456600D01*
X-1036600Y-456800D01*
G01X-1031100Y-472500D02*
X-1031400Y-470900D01*
X-1031900Y-472200D01*
X-1035200D01*
Y-467600D01*
X-1032000Y-453700D01*
X-1030500Y-453800D01*
X-1030000Y-456700D01*
X-1033400Y-471900D01*
X-1034300Y-471600D01*
X-1034200Y-467100D01*
X-1031400Y-454500D01*
X-1030700Y-456500D01*
X-1033700Y-470600D01*
X-1032700Y-461100D01*
G01X-1032000Y-452900D02*
X-1029300D01*
X-1028000Y-457000D01*
X-1029500Y-453600D01*
X-1029100Y-457300D01*
X-1032800Y-472800D01*
X-1030200Y-472600D01*
G54D14*
X-1615984Y-178583D03*
X-1608110Y-167165D03*
X-1615984Y-162047D03*
Y-151024D03*
X-1608110Y-150630D03*
X-1615984Y-140000D03*
Y-145512D03*
X-1608110Y-134094D03*
Y-117559D03*
X-1615984Y-112441D03*
X-1608110Y-112047D03*
Y-106535D03*
Y-101024D03*
X-1615984Y-95906D03*
X-1592362Y-167165D03*
X-1600236Y-178583D03*
X-1592362Y-150630D03*
X-1600236Y-162047D03*
X-1592362Y-134094D03*
X-1600236Y-145512D03*
Y-128976D03*
X-1592362Y-117559D03*
X-1600236Y-112441D03*
X-1592362Y-101024D03*
X-1600236Y-95906D03*
X-1576614Y-167165D03*
X-1584488Y-178583D03*
X-1576614Y-150630D03*
X-1584488Y-162047D03*
X-1576614Y-134094D03*
X-1584488Y-145512D03*
Y-128976D03*
X-1576614Y-117559D03*
Y-101024D03*
X-1584488Y-112441D03*
Y-95906D03*
X-1560866Y-167165D03*
X-1568740Y-178583D03*
X-1560866Y-150630D03*
X-1568740Y-162047D03*
X-1560866Y-134094D03*
X-1568740Y-145512D03*
Y-128976D03*
X-1560866Y-117559D03*
X-1568740Y-112441D03*
X-1560866Y-101024D03*
X-1568740Y-95906D03*
X-1545118Y-167165D03*
X-1552992Y-178583D03*
X-1545118Y-150630D03*
X-1552992Y-162047D03*
X-1545118Y-134094D03*
X-1552992Y-145512D03*
Y-128976D03*
X-1545118Y-117559D03*
X-1552992Y-112441D03*
X-1545118Y-101024D03*
X-1552992Y-95906D03*
X-1189134Y-167559D03*
X-1197008Y-178976D03*
X-1189134Y-151024D03*
X-1197008Y-162441D03*
Y-145906D03*
Y-129370D03*
X-1173386Y-167559D03*
X-1181260Y-178976D03*
Y-162441D03*
Y-129370D03*
X-1157638Y-167559D03*
X-1165512Y-178976D03*
X-1157638Y-151024D03*
X-1165512Y-162441D03*
X-1157638Y-134488D03*
X-1165512Y-145906D03*
Y-129370D03*
X-1014488Y-178976D03*
Y-162441D03*
Y-145906D03*
Y-129370D03*
X-1006614Y-167559D03*
X-998740Y-178976D03*
X-1006614Y-151024D03*
X-998740Y-162441D03*
X-1006614Y-134488D03*
X-998740Y-145906D03*
Y-129370D03*
X-990866Y-167559D03*
X-982992Y-178976D03*
X-990866Y-151024D03*
X-982992Y-162441D03*
X-990866Y-134488D03*
X-982992Y-145906D03*
Y-129370D03*
X-975118Y-167559D03*
Y-151024D03*
Y-134488D03*
X-745906Y-178583D03*
Y-162047D03*
Y-151024D03*
Y-140000D03*
Y-145512D03*
Y-112441D03*
Y-95906D03*
X-738032Y-167165D03*
X-730157Y-178583D03*
X-738032Y-150630D03*
X-730157Y-162047D03*
X-738032Y-134094D03*
X-730157Y-145512D03*
Y-128976D03*
X-738032Y-117559D03*
X-730157Y-112441D03*
X-738032Y-112047D03*
Y-106535D03*
Y-101024D03*
X-730157Y-95906D03*
X-722283Y-167165D03*
X-714409Y-178583D03*
X-722283Y-150630D03*
X-714409Y-162047D03*
X-722283Y-134094D03*
X-714409Y-145512D03*
X-722283Y-117559D03*
X-714409Y-128976D03*
X-722283Y-101024D03*
X-714409Y-112441D03*
Y-95906D03*
X-706535Y-167165D03*
X-698661Y-178583D03*
X-706535Y-150630D03*
X-698661Y-162047D03*
X-706535Y-134094D03*
X-698661Y-145512D03*
X-706535Y-117559D03*
X-698661Y-128976D03*
X-706535Y-101024D03*
X-698661Y-112441D03*
Y-95906D03*
X-690787Y-167165D03*
X-682913Y-178583D03*
X-690787Y-150630D03*
X-682913Y-162047D03*
X-690787Y-134094D03*
X-682913Y-145512D03*
Y-128976D03*
X-690787Y-117559D03*
Y-101024D03*
X-682913Y-112441D03*
Y-95906D03*
X-675039Y-167165D03*
Y-150630D03*
Y-134094D03*
Y-117559D03*
Y-101024D03*
X-319055Y-167559D03*
X-326929Y-178976D03*
X-319055Y-151024D03*
X-326929Y-162441D03*
Y-145906D03*
Y-129370D03*
X-303307Y-167559D03*
X-311181Y-178976D03*
Y-162441D03*
Y-129370D03*
X-287559Y-167559D03*
X-295433Y-178976D03*
X-287559Y-151024D03*
X-295433Y-162441D03*
X-287559Y-134488D03*
X-295433Y-145906D03*
Y-129370D03*
X-144409Y-178976D03*
Y-162441D03*
Y-145906D03*
Y-129370D03*
X-136535Y-167559D03*
X-128661Y-178976D03*
X-136535Y-151024D03*
X-128661Y-162441D03*
X-136535Y-134488D03*
X-128661Y-145906D03*
Y-129370D03*
X-120787Y-167559D03*
X-112913Y-178976D03*
X-120787Y-151024D03*
X-112913Y-162441D03*
X-120787Y-134488D03*
X-112913Y-145906D03*
Y-129370D03*
X-105039Y-167559D03*
Y-151024D03*
Y-134488D03*
G54D24*
G01X-1186050Y-540000D02*
Y-552500D01*
X-1180250D01*
G01X-1174975D02*
X-1171350Y-540000D01*
X-1167725Y-552500D01*
G01X-1169030Y-548125D02*
X-1173670D01*
G01X-1159550Y-552500D02*
Y-546875D01*
X-1162450Y-540000D01*
G01X-1156650D02*
X-1159550Y-546875D01*
G01X-1144850Y-552500D02*
X-1150650D01*
Y-540000D01*
X-1144850D01*
G01X-1147170Y-546042D02*
X-1150650D01*
G01X-1138850Y-552500D02*
Y-540000D01*
X-1135225D01*
X-1134065Y-540625D01*
X-1133340Y-541458D01*
X-1133050Y-543125D01*
X-1133340Y-544792D01*
X-1134210Y-545833D01*
X-1135225Y-546458D01*
X-1138850D01*
G01X-1135225D02*
X-1133050Y-552500D01*
G01X-1115105Y-542083D02*
X-1114235Y-540834D01*
X-1113220Y-540208D01*
X-1112060Y-540000D01*
X-1110610Y-540417D01*
X-1109595Y-541458D01*
X-1109305Y-542708D01*
X-1109450Y-543959D01*
X-1110030Y-545000D01*
X-1112930Y-547083D01*
X-1114235Y-548542D01*
X-1115105Y-550625D01*
X-1115395Y-552500D01*
X-1109305D01*
G54D15*
X-1356889Y-167165D03*
Y-118937D03*
X-1051613Y-167165D03*
Y-118937D03*
X-486810Y-167165D03*
Y-118937D03*
X-181534Y-167165D03*
Y-118937D03*
G54D25*
G01X-1652043Y-100921D02*
X-1649000Y-97878D01*
G01D02*
X-1645957Y-94835D01*
G01X-1652043D02*
X-1649000Y-97878D01*
G01D02*
X-1645957Y-100921D01*
G01X-1185925Y-592500D02*
X-1178575Y-577500D01*
G01X-1185925D02*
X-1178575Y-592500D01*
G01X-1168050D02*
X-1166825Y-592250D01*
X-1165425Y-591500D01*
X-1164550Y-590250D01*
X-1164200Y-588500D01*
X-1164550Y-586750D01*
X-1165600Y-585250D01*
X-1167175Y-584500D01*
X-1168925D01*
X-1169975Y-584000D01*
X-1170850Y-582750D01*
X-1171200Y-581000D01*
X-1170675Y-579250D01*
X-1169450Y-578000D01*
X-1168050Y-577500D01*
X-1166650Y-578000D01*
X-1165425Y-579250D01*
X-1164900Y-581000D01*
X-1165250Y-582750D01*
X-1166125Y-584000D01*
X-1167175Y-584500D01*
X-1168925D01*
X-1170500Y-585250D01*
X-1171550Y-586750D01*
X-1171900Y-588500D01*
X-1171550Y-590250D01*
X-1170675Y-591500D01*
X-1169275Y-592250D01*
X-1168050Y-592500D01*
G01X-1153850D02*
X-1152625Y-592250D01*
X-1151225Y-591500D01*
X-1150350Y-590250D01*
X-1150000Y-588500D01*
X-1150350Y-586750D01*
X-1151400Y-585250D01*
X-1152975Y-584500D01*
X-1154725D01*
X-1155775Y-584000D01*
X-1156650Y-582750D01*
X-1157000Y-581000D01*
X-1156475Y-579250D01*
X-1155250Y-578000D01*
X-1153850Y-577500D01*
X-1152450Y-578000D01*
X-1151225Y-579250D01*
X-1150700Y-581000D01*
X-1151050Y-582750D01*
X-1151925Y-584000D01*
X-1152975Y-584500D01*
X-1154725D01*
X-1156300Y-585250D01*
X-1157350Y-586750D01*
X-1157700Y-588500D01*
X-1157350Y-590250D01*
X-1156475Y-591500D01*
X-1155075Y-592250D01*
X-1153850Y-592500D01*
G01X-1140000D02*
X-1139650Y-589250D01*
X-1139125Y-586500D01*
X-1138425Y-584000D01*
X-1137550Y-581250D01*
X-1136150Y-577500D01*
X-1143150D01*
G01X-1129300Y-590250D02*
X-1128250Y-591500D01*
X-1127025Y-592250D01*
X-1125450Y-592500D01*
X-1123875Y-592000D01*
X-1122650Y-591000D01*
X-1121775Y-589250D01*
X-1121600Y-587250D01*
X-1121950Y-585250D01*
X-1122825Y-584000D01*
X-1124050Y-583000D01*
X-1125275Y-582750D01*
X-1126500Y-583000D01*
X-1128075Y-584000D01*
X-1127550Y-577500D01*
X-1122825D01*
G01X-1111600Y-592500D02*
X-1111250Y-589250D01*
X-1110725Y-586500D01*
X-1110025Y-584000D01*
X-1109150Y-581250D01*
X-1107750Y-577500D01*
X-1114750D01*
G01X-1097050Y-592500D02*
Y-577500D01*
X-1099150Y-580500D01*
G01Y-592500D02*
X-1094950D01*
G01X-1085125Y-587500D02*
X-1080575D01*
G01X-1068650Y-577500D02*
X-1070050Y-578000D01*
X-1071100Y-579250D01*
X-1071800Y-580750D01*
X-1072325Y-582750D01*
X-1072500Y-585000D01*
X-1072325Y-587250D01*
X-1071800Y-589250D01*
X-1071100Y-590750D01*
X-1070050Y-592000D01*
X-1068650Y-592500D01*
X-1067250Y-592000D01*
X-1066200Y-590750D01*
X-1065500Y-589250D01*
X-1064975Y-587250D01*
X-1064800Y-585000D01*
X-1064975Y-582750D01*
X-1065500Y-580750D01*
X-1066200Y-579250D01*
X-1067250Y-578000D01*
X-1068650Y-577500D01*
G01X-1054450D02*
X-1055850Y-578000D01*
X-1056900Y-579250D01*
X-1057600Y-580750D01*
X-1058125Y-582750D01*
X-1058300Y-585000D01*
X-1058125Y-587250D01*
X-1057600Y-589250D01*
X-1056900Y-590750D01*
X-1055850Y-592000D01*
X-1054450Y-592500D01*
X-1053050Y-592000D01*
X-1052000Y-590750D01*
X-1051300Y-589250D01*
X-1050775Y-587250D01*
X-1050600Y-585000D01*
X-1050775Y-582750D01*
X-1051300Y-580750D01*
X-1052000Y-579250D01*
X-1053050Y-578000D01*
X-1054450Y-577500D01*
G01X-1044100Y-590250D02*
X-1043050Y-591500D01*
X-1041825Y-592250D01*
X-1040250Y-592500D01*
X-1038675Y-592000D01*
X-1037450Y-591000D01*
X-1036575Y-589250D01*
X-1036400Y-587250D01*
X-1036750Y-585250D01*
X-1037625Y-584000D01*
X-1038850Y-583000D01*
X-1040075Y-582750D01*
X-1041300Y-583000D01*
X-1042875Y-584000D01*
X-1042350Y-577500D01*
X-1037625D01*
G01X-911875Y-592500D02*
X-907500Y-577500D01*
X-903125Y-592500D01*
G01X-904700Y-587250D02*
X-910300D01*
G01X-810781Y-103562D02*
X-806854Y-99635D01*
G01D02*
X-802927Y-95708D01*
G01X-810781D02*
X-806854Y-99635D01*
G01D02*
X-802927Y-103562D01*
G01X-796771Y-141271D02*
X-793728Y-138228D01*
G01D02*
X-790685Y-135185D01*
G01X-796771D02*
X-793728Y-138228D01*
G01D02*
X-790685Y-141271D01*
G01X-789127Y-103562D02*
X-785200Y-99635D01*
G01X-789127Y-95708D02*
X-785200Y-99635D01*
G01D02*
X-781273Y-103562D01*
G01X-785200Y-99635D02*
X-781273Y-95708D01*
G54D16*
X-1356889Y-145000D03*
X-1051613D03*
X-486810D03*
X-181534D03*
G54D26*
G01X-1200000Y-560000D02*
X-890000D01*
G01Y-520000D02*
X-1200000D01*
G01X-575000Y-480000D02*
X-1200000D01*
G01X-927500Y-560000D02*
Y-600000D01*
G01X-915000Y-440000D02*
Y-480000D01*
G01X-890000D02*
Y-600000D01*
G01X-870000Y-440000D02*
Y-480000D01*
G01X-680000D02*
Y-440000D01*
G01X-1200000Y-600000D02*
X-575000D01*
Y-440000D01*
X-1200000D01*
Y-600000D01*
G54D17*
X-1282480Y-172283D03*
Y-130157D03*
Y-94724D03*
Y-59291D03*
Y-23858D03*
X-1253740Y-184094D03*
X-1225394D03*
X-1207677Y-154567D03*
Y-112441D03*
Y-77008D03*
Y-41575D03*
Y-6142D03*
X-412402Y-172283D03*
Y-130157D03*
Y-94724D03*
Y-59291D03*
Y-23858D03*
X-383661Y-184094D03*
X-355315D03*
X-337598Y-154567D03*
Y-112441D03*
Y-77008D03*
Y-41575D03*
Y-6142D03*
G54D27*
G01X-1007500Y-470000D02*
X-1006450Y-475000D01*
X-1005250Y-470000D01*
X-1004050Y-475000D01*
X-1003000Y-470000D01*
G01X-1001125Y-475000D02*
X-999250Y-470000D01*
X-997375Y-475000D01*
G01X-998050Y-473250D02*
X-1000450D01*
G01X-994825Y-474333D02*
X-994225Y-474750D01*
X-993550Y-475000D01*
X-992950D01*
X-992350Y-474750D01*
X-991900Y-474333D01*
X-991675Y-473750D01*
X-991825Y-473167D01*
X-992200Y-472667D01*
X-992875Y-472333D01*
X-993775Y-472167D01*
X-994300Y-471833D01*
X-994525Y-471250D01*
X-994375Y-470667D01*
X-994000Y-470250D01*
X-993475Y-470000D01*
X-992950D01*
X-992425Y-470167D01*
X-991975Y-470583D01*
G01X-988825Y-475000D02*
Y-470000D01*
G01X-985675D02*
Y-475000D01*
G01Y-472500D02*
X-988825D01*
G01X-976525Y-474417D02*
X-976000Y-474833D01*
X-975400Y-475000D01*
X-974800Y-474833D01*
X-974275Y-474333D01*
X-973900Y-473583D01*
X-973750Y-472833D01*
Y-471917D01*
X-973900Y-471167D01*
X-974275Y-470500D01*
X-974725Y-470167D01*
X-975250Y-470000D01*
X-975850Y-470167D01*
X-976300Y-470500D01*
X-976600Y-471000D01*
X-976750Y-471667D01*
X-976600Y-472250D01*
X-976225Y-472833D01*
X-975775Y-473167D01*
X-975250Y-473250D01*
X-974650Y-473083D01*
X-974200Y-472667D01*
X-973750Y-471917D01*
G01X-969250Y-475000D02*
X-968725Y-474917D01*
X-968125Y-474667D01*
X-967750Y-474250D01*
X-967600Y-473667D01*
X-967750Y-473083D01*
X-968200Y-472583D01*
X-968875Y-472333D01*
X-969625D01*
X-970075Y-472167D01*
X-970450Y-471750D01*
X-970600Y-471167D01*
X-970375Y-470583D01*
X-969850Y-470167D01*
X-969250Y-470000D01*
X-968650Y-470167D01*
X-968125Y-470583D01*
X-967900Y-471167D01*
X-968050Y-471750D01*
X-968425Y-472167D01*
X-968875Y-472333D01*
X-969625D01*
X-970300Y-472583D01*
X-970750Y-473083D01*
X-970900Y-473667D01*
X-970750Y-474250D01*
X-970375Y-474667D01*
X-969775Y-474917D01*
X-969250Y-475000D01*
G01X-963250Y-470000D02*
X-963850Y-470167D01*
X-964300Y-470583D01*
X-964600Y-471083D01*
X-964825Y-471750D01*
X-964900Y-472500D01*
X-964825Y-473250D01*
X-964600Y-473917D01*
X-964300Y-474417D01*
X-963850Y-474833D01*
X-963250Y-475000D01*
X-962650Y-474833D01*
X-962200Y-474417D01*
X-961900Y-473917D01*
X-961675Y-473250D01*
X-961600Y-472500D01*
X-961675Y-471750D01*
X-961900Y-471083D01*
X-962200Y-470583D01*
X-962650Y-470167D01*
X-963250Y-470000D01*
G01X-958900Y-474250D02*
X-958450Y-474667D01*
X-957925Y-474917D01*
X-957250Y-475000D01*
X-956575Y-474833D01*
X-956050Y-474500D01*
X-955675Y-473917D01*
X-955600Y-473250D01*
X-955750Y-472583D01*
X-956125Y-472167D01*
X-956650Y-471833D01*
X-957175Y-471750D01*
X-957700Y-471833D01*
X-958375Y-472167D01*
X-958150Y-470000D01*
X-956125D01*
G01X-952675Y-470833D02*
X-952225Y-470333D01*
X-951700Y-470083D01*
X-951100Y-470000D01*
X-950350Y-470167D01*
X-949825Y-470583D01*
X-949675Y-471083D01*
X-949750Y-471583D01*
X-950050Y-472000D01*
X-951550Y-472833D01*
X-952225Y-473417D01*
X-952675Y-474250D01*
X-952825Y-475000D01*
X-949675D01*
G01X-946225Y-473333D02*
X-944275D01*
G01X-940675Y-472917D02*
X-940150Y-472333D01*
X-939700Y-472000D01*
X-939100Y-471833D01*
X-938575Y-472000D01*
X-938200Y-472333D01*
X-937900Y-472833D01*
X-937825Y-473417D01*
X-937900Y-473917D01*
X-938200Y-474417D01*
X-938650Y-474833D01*
X-939175Y-475000D01*
X-939775Y-474833D01*
X-940300Y-474333D01*
X-940600Y-473583D01*
X-940675Y-472750D01*
X-940525Y-471667D01*
X-940300Y-471083D01*
X-939925Y-470500D01*
X-939400Y-470083D01*
X-938875Y-470000D01*
X-938350Y-470167D01*
X-937975Y-470583D01*
G01X-934900Y-474000D02*
X-934450Y-474583D01*
X-933850Y-474917D01*
X-933175Y-475000D01*
X-932575Y-474917D01*
X-931975Y-474500D01*
X-931600Y-474000D01*
X-931525Y-473500D01*
X-931675Y-472917D01*
X-932200Y-472500D01*
X-932725Y-472333D01*
X-933400D01*
G01X-932725D02*
X-932275Y-472083D01*
X-931900Y-471667D01*
X-931750Y-471167D01*
X-931900Y-470667D01*
X-932275Y-470250D01*
X-932950Y-470000D01*
X-933625Y-470083D01*
X-934300Y-470417D01*
G01X-928525Y-474417D02*
X-928000Y-474833D01*
X-927400Y-475000D01*
X-926800Y-474833D01*
X-926275Y-474333D01*
X-925900Y-473583D01*
X-925750Y-472833D01*
Y-471917D01*
X-925900Y-471167D01*
X-926275Y-470500D01*
X-926725Y-470167D01*
X-927250Y-470000D01*
X-927850Y-470167D01*
X-928300Y-470500D01*
X-928600Y-471000D01*
X-928750Y-471667D01*
X-928600Y-472250D01*
X-928225Y-472833D01*
X-927775Y-473167D01*
X-927250Y-473250D01*
X-926650Y-473083D01*
X-926200Y-472667D01*
X-925750Y-471917D01*
G01X-922525Y-474417D02*
X-922000Y-474833D01*
X-921400Y-475000D01*
X-920800Y-474833D01*
X-920275Y-474333D01*
X-919900Y-473583D01*
X-919750Y-472833D01*
Y-471917D01*
X-919900Y-471167D01*
X-920275Y-470500D01*
X-920725Y-470167D01*
X-921250Y-470000D01*
X-921850Y-470167D01*
X-922300Y-470500D01*
X-922600Y-471000D01*
X-922750Y-471667D01*
X-922600Y-472250D01*
X-922225Y-472833D01*
X-921775Y-473167D01*
X-921250Y-473250D01*
X-920650Y-473083D01*
X-920200Y-472667D01*
X-919750Y-471917D01*
G01X-1006750Y-465000D02*
Y-460000D01*
X-1004875D01*
X-1004275Y-460250D01*
X-1003900Y-460583D01*
X-1003750Y-461250D01*
X-1003900Y-461917D01*
X-1004350Y-462333D01*
X-1004875Y-462583D01*
X-1006750D01*
G01X-1004875D02*
X-1003750Y-465000D01*
G01X-997750D02*
X-1000750D01*
Y-460000D01*
X-997750D01*
G01X-998950Y-462417D02*
X-1000750D01*
G01X-994900Y-465000D02*
Y-460000D01*
X-993400D01*
X-992800Y-460250D01*
X-992350Y-460583D01*
X-991975Y-461083D01*
X-991675Y-461667D01*
X-991600Y-462500D01*
X-991675Y-463333D01*
X-991975Y-463917D01*
X-992350Y-464417D01*
X-992800Y-464750D01*
X-993400Y-465000D01*
X-994900D01*
G01X-989200D02*
Y-460000D01*
X-987250Y-464167D01*
X-985300Y-460000D01*
Y-465000D01*
G01X-981250D02*
X-981850Y-464917D01*
X-982375Y-464583D01*
X-982825Y-464083D01*
X-983125Y-463500D01*
X-983275Y-462833D01*
Y-462167D01*
X-983125Y-461500D01*
X-982825Y-460917D01*
X-982375Y-460417D01*
X-981850Y-460083D01*
X-981250Y-460000D01*
X-980650Y-460083D01*
X-980125Y-460417D01*
X-979675Y-460917D01*
X-979375Y-461500D01*
X-979225Y-462167D01*
Y-462833D01*
X-979375Y-463500D01*
X-979675Y-464083D01*
X-980125Y-464583D01*
X-980650Y-464917D01*
X-981250Y-465000D01*
G01X-976975D02*
Y-460000D01*
X-973525Y-465000D01*
Y-460000D01*
G01X-970900Y-465000D02*
Y-460000D01*
X-969400D01*
X-968800Y-460250D01*
X-968350Y-460583D01*
X-967975Y-461083D01*
X-967675Y-461667D01*
X-967600Y-462500D01*
X-967675Y-463333D01*
X-967975Y-463917D01*
X-968350Y-464417D01*
X-968800Y-464750D01*
X-969400Y-465000D01*
X-970900D01*
G01X-1005250Y-455000D02*
Y-450000D01*
X-1006150Y-451000D01*
G01Y-455000D02*
X-1004350D01*
G01X-995200D02*
Y-450000D01*
X-993250Y-454167D01*
X-991300Y-450000D01*
Y-455000D01*
G01X-988150Y-450000D02*
X-986350D01*
G01X-987250D02*
Y-455000D01*
G01X-988150D02*
X-986350D01*
G01X-979600Y-450417D02*
X-980050Y-450167D01*
X-980575Y-450000D01*
X-981175D01*
X-981850Y-450250D01*
X-982375Y-450667D01*
X-982750Y-451167D01*
X-983050Y-452000D01*
X-983125Y-452750D01*
X-982975Y-453500D01*
X-982750Y-454000D01*
X-982300Y-454500D01*
X-981775Y-454833D01*
X-981250Y-455000D01*
X-980725D01*
X-980200Y-454833D01*
X-979750Y-454583D01*
X-979375Y-454250D01*
G01X-976750Y-455000D02*
Y-450000D01*
X-974875D01*
X-974275Y-450250D01*
X-973900Y-450583D01*
X-973750Y-451250D01*
X-973900Y-451917D01*
X-974350Y-452333D01*
X-974875Y-452583D01*
X-976750D01*
G01X-974875D02*
X-973750Y-455000D01*
G01X-969250D02*
X-969850Y-454917D01*
X-970375Y-454583D01*
X-970825Y-454083D01*
X-971125Y-453500D01*
X-971275Y-452833D01*
Y-452167D01*
X-971125Y-451500D01*
X-970825Y-450917D01*
X-970375Y-450417D01*
X-969850Y-450083D01*
X-969250Y-450000D01*
X-968650Y-450083D01*
X-968125Y-450417D01*
X-967675Y-450917D01*
X-967375Y-451500D01*
X-967225Y-452167D01*
Y-452833D01*
X-967375Y-453500D01*
X-967675Y-454083D01*
X-968125Y-454583D01*
X-968650Y-454917D01*
X-969250Y-455000D01*
G01X-964825Y-454333D02*
X-964225Y-454750D01*
X-963550Y-455000D01*
X-962950D01*
X-962350Y-454750D01*
X-961900Y-454333D01*
X-961675Y-453750D01*
X-961825Y-453167D01*
X-962200Y-452667D01*
X-962875Y-452333D01*
X-963775Y-452167D01*
X-964300Y-451833D01*
X-964525Y-451250D01*
X-964375Y-450667D01*
X-964000Y-450250D01*
X-963475Y-450000D01*
X-962950D01*
X-962425Y-450167D01*
X-961975Y-450583D01*
G01X-957250Y-455000D02*
X-957850Y-454917D01*
X-958375Y-454583D01*
X-958825Y-454083D01*
X-959125Y-453500D01*
X-959275Y-452833D01*
Y-452167D01*
X-959125Y-451500D01*
X-958825Y-450917D01*
X-958375Y-450417D01*
X-957850Y-450083D01*
X-957250Y-450000D01*
X-956650Y-450083D01*
X-956125Y-450417D01*
X-955675Y-450917D01*
X-955375Y-451500D01*
X-955225Y-452167D01*
Y-452833D01*
X-955375Y-453500D01*
X-955675Y-454083D01*
X-956125Y-454583D01*
X-956650Y-454917D01*
X-957250Y-455000D01*
G01X-952675D02*
Y-450000D01*
X-949825D01*
G01X-950875Y-452417D02*
X-952675D01*
G01X-945250Y-450000D02*
Y-455000D01*
G01X-946975Y-450000D02*
X-943525D01*
G01X-935500D02*
X-934450Y-455000D01*
X-933250Y-450000D01*
X-932050Y-455000D01*
X-931000Y-450000D01*
G01X-929125Y-455000D02*
X-927250Y-450000D01*
X-925375Y-455000D01*
G01X-926050Y-453250D02*
X-928450D01*
G01X-921250Y-455000D02*
Y-452750D01*
X-922750Y-450000D01*
G01X-919750D02*
X-921250Y-452750D01*
G54D18*
X-1141240Y-132520D03*
Y-112835D03*
Y-94331D03*
X-1132087Y-150630D03*
X-1113189D03*
X-1094291D03*
X-1085138Y-132520D03*
Y-112835D03*
Y-94331D03*
X-271161Y-132520D03*
Y-112835D03*
Y-94331D03*
X-262008Y-150630D03*
X-243110D03*
X-224213D03*
X-215059Y-132520D03*
Y-112835D03*
Y-94331D03*
G54D28*
G01X-874510Y-499000D02*
Y-493000D01*
X-871290Y-499000D01*
Y-493000D01*
G01X-867200Y-499000D02*
X-867760Y-498900D01*
X-868250Y-498500D01*
X-868670Y-497900D01*
X-868950Y-497200D01*
X-869090Y-496400D01*
Y-495600D01*
X-868950Y-494800D01*
X-868670Y-494100D01*
X-868250Y-493500D01*
X-867760Y-493100D01*
X-867200Y-493000D01*
X-866640Y-493100D01*
X-866150Y-493500D01*
X-865730Y-494100D01*
X-865450Y-494800D01*
X-865310Y-495600D01*
Y-496400D01*
X-865450Y-497200D01*
X-865730Y-497900D01*
X-866150Y-498500D01*
X-866640Y-498900D01*
X-867200Y-499000D01*
G01X-861500Y-493000D02*
Y-499000D01*
G01X-863110Y-493000D02*
X-859890D01*
G01X-856640D02*
X-854960D01*
G01X-855800D02*
Y-499000D01*
G01X-856640D02*
X-854960D01*
G01X-848560Y-493500D02*
X-848980Y-493200D01*
X-849470Y-493000D01*
X-850030D01*
X-850660Y-493300D01*
X-851150Y-493800D01*
X-851500Y-494400D01*
X-851780Y-495400D01*
X-851850Y-496300D01*
X-851710Y-497200D01*
X-851500Y-497800D01*
X-851080Y-498400D01*
X-850590Y-498800D01*
X-850100Y-499000D01*
X-849610D01*
X-849120Y-498800D01*
X-848700Y-498500D01*
X-848350Y-498100D01*
G01X-843000Y-499000D02*
X-845800D01*
Y-493000D01*
X-843000D01*
G01X-844120Y-495900D02*
X-845800D01*
G01X-833000Y-499000D02*
X-833560Y-498900D01*
X-834050Y-498500D01*
X-834470Y-497900D01*
X-834750Y-497200D01*
X-834890Y-496400D01*
Y-495600D01*
X-834750Y-494800D01*
X-834470Y-494100D01*
X-834050Y-493500D01*
X-833560Y-493100D01*
X-833000Y-493000D01*
X-832440Y-493100D01*
X-831950Y-493500D01*
X-831530Y-494100D01*
X-831250Y-494800D01*
X-831110Y-495600D01*
Y-496400D01*
X-831250Y-497200D01*
X-831530Y-497900D01*
X-831950Y-498500D01*
X-832440Y-498900D01*
X-833000Y-499000D01*
G01X-828630D02*
Y-493000D01*
X-825970D01*
G01X-826950Y-495900D02*
X-828630D01*
G01X-817300Y-499000D02*
Y-493000D01*
X-815620D01*
X-815060Y-493300D01*
X-814640Y-494000D01*
X-814500Y-494800D01*
X-814640Y-495600D01*
X-814990Y-496200D01*
X-815620Y-496500D01*
X-817300D01*
G01X-811600Y-499000D02*
Y-493000D01*
X-809850D01*
X-809290Y-493300D01*
X-808940Y-493700D01*
X-808800Y-494500D01*
X-808940Y-495300D01*
X-809360Y-495800D01*
X-809850Y-496100D01*
X-811600D01*
G01X-809850D02*
X-808800Y-499000D01*
G01X-804500D02*
X-805060Y-498900D01*
X-805550Y-498500D01*
X-805970Y-497900D01*
X-806250Y-497200D01*
X-806390Y-496400D01*
Y-495600D01*
X-806250Y-494800D01*
X-805970Y-494100D01*
X-805550Y-493500D01*
X-805060Y-493100D01*
X-804500Y-493000D01*
X-803940Y-493100D01*
X-803450Y-493500D01*
X-803030Y-494100D01*
X-802750Y-494800D01*
X-802610Y-495600D01*
Y-496400D01*
X-802750Y-497200D01*
X-803030Y-497900D01*
X-803450Y-498500D01*
X-803940Y-498900D01*
X-804500Y-499000D01*
G01X-800200D02*
Y-493000D01*
X-798520D01*
X-797960Y-493300D01*
X-797540Y-494000D01*
X-797400Y-494800D01*
X-797540Y-495600D01*
X-797890Y-496200D01*
X-798520Y-496500D01*
X-800200D01*
G01X-794500Y-499000D02*
Y-493000D01*
X-792750D01*
X-792190Y-493300D01*
X-791840Y-493700D01*
X-791700Y-494500D01*
X-791840Y-495300D01*
X-792260Y-495800D01*
X-792750Y-496100D01*
X-794500D01*
G01X-792750D02*
X-791700Y-499000D01*
G01X-788240Y-493000D02*
X-786560D01*
G01X-787400D02*
Y-499000D01*
G01X-788240D02*
X-786560D01*
G01X-780300D02*
X-783100D01*
Y-493000D01*
X-780300D01*
G01X-781420Y-495900D02*
X-783100D01*
G01X-776000Y-493000D02*
Y-499000D01*
G01X-777610Y-493000D02*
X-774390D01*
G01X-772050Y-499000D02*
X-770300Y-493000D01*
X-768550Y-499000D01*
G01X-769180Y-496900D02*
X-771420D01*
G01X-766000Y-499000D02*
Y-493000D01*
X-764250D01*
X-763690Y-493300D01*
X-763340Y-493700D01*
X-763200Y-494500D01*
X-763340Y-495300D01*
X-763760Y-495800D01*
X-764250Y-496100D01*
X-766000D01*
G01X-764250D02*
X-763200Y-499000D01*
G01X-758900D02*
Y-496300D01*
X-760300Y-493000D01*
G01X-757500D02*
X-758900Y-496300D01*
G01X-748900Y-499000D02*
Y-493000D01*
X-747220D01*
X-746660Y-493300D01*
X-746240Y-494000D01*
X-746100Y-494800D01*
X-746240Y-495600D01*
X-746590Y-496200D01*
X-747220Y-496500D01*
X-748900D01*
G01X-743200Y-499000D02*
Y-493000D01*
X-741450D01*
X-740890Y-493300D01*
X-740540Y-493700D01*
X-740400Y-494500D01*
X-740540Y-495300D01*
X-740960Y-495800D01*
X-741450Y-496100D01*
X-743200D01*
G01X-741450D02*
X-740400Y-499000D01*
G01X-736100D02*
X-736660Y-498900D01*
X-737150Y-498500D01*
X-737570Y-497900D01*
X-737850Y-497200D01*
X-737990Y-496400D01*
Y-495600D01*
X-737850Y-494800D01*
X-737570Y-494100D01*
X-737150Y-493500D01*
X-736660Y-493100D01*
X-736100Y-493000D01*
X-735540Y-493100D01*
X-735050Y-493500D01*
X-734630Y-494100D01*
X-734350Y-494800D01*
X-734210Y-495600D01*
Y-496400D01*
X-734350Y-497200D01*
X-734630Y-497900D01*
X-735050Y-498500D01*
X-735540Y-498900D01*
X-736100Y-499000D01*
G01X-731800D02*
Y-493000D01*
X-730120D01*
X-729560Y-493300D01*
X-729140Y-494000D01*
X-729000Y-494800D01*
X-729140Y-495600D01*
X-729490Y-496200D01*
X-730120Y-496500D01*
X-731800D01*
G01X-723300Y-499000D02*
X-726100D01*
Y-493000D01*
X-723300D01*
G01X-724420Y-495900D02*
X-726100D01*
G01X-720400Y-499000D02*
Y-493000D01*
X-718650D01*
X-718090Y-493300D01*
X-717740Y-493700D01*
X-717600Y-494500D01*
X-717740Y-495300D01*
X-718160Y-495800D01*
X-718650Y-496100D01*
X-720400D01*
G01X-718650D02*
X-717600Y-499000D01*
G01X-713300Y-493000D02*
Y-499000D01*
G01X-714910Y-493000D02*
X-711690D01*
G01X-707600Y-499000D02*
Y-496300D01*
X-709000Y-493000D01*
G01X-706200D02*
X-707600Y-496300D01*
G01X-701900Y-499200D02*
X-702040Y-499100D01*
Y-498900D01*
X-701900Y-498800D01*
X-701760Y-498900D01*
Y-499100D01*
X-701900Y-499200D01*
G01Y-496500D02*
X-702040Y-496400D01*
Y-496200D01*
X-701900Y-496100D01*
X-701760Y-496200D01*
Y-496400D01*
X-701900Y-496500D01*
G54D19*
X-1141240Y-142362D03*
Y-102992D03*
Y-63622D03*
Y-24252D03*
X-1128760Y-83307D03*
X-1118917Y-4567D03*
X-1107500Y-83307D03*
X-1085138Y-122677D03*
Y-83307D03*
Y-43937D03*
Y-4567D03*
X-806854Y-99635D03*
X-785200D03*
X-271161Y-142362D03*
Y-102992D03*
Y-63622D03*
Y-24252D03*
X-258681Y-83307D03*
X-237421D03*
X-248839Y-4567D03*
X-215059Y-122677D03*
Y-83307D03*
Y-43937D03*
Y-4567D03*
G54D29*
G01X-1189333Y-572500D02*
Y-565500D01*
X-1187667D01*
X-1187000Y-565850D01*
X-1186500Y-566317D01*
X-1186083Y-567017D01*
X-1185750Y-567833D01*
X-1185667Y-569000D01*
X-1185750Y-570167D01*
X-1186083Y-570983D01*
X-1186500Y-571684D01*
X-1187000Y-572150D01*
X-1187667Y-572500D01*
X-1189333D01*
G01X-1180700D02*
X-1181367Y-572383D01*
X-1181950Y-571917D01*
X-1182450Y-571217D01*
X-1182783Y-570400D01*
X-1182950Y-569467D01*
Y-568533D01*
X-1182783Y-567600D01*
X-1182450Y-566783D01*
X-1181950Y-566083D01*
X-1181367Y-565617D01*
X-1180700Y-565500D01*
X-1180033Y-565617D01*
X-1179450Y-566083D01*
X-1178950Y-566783D01*
X-1178617Y-567600D01*
X-1178450Y-568533D01*
Y-569467D01*
X-1178617Y-570400D01*
X-1178950Y-571217D01*
X-1179450Y-571917D01*
X-1180033Y-572383D01*
X-1180700Y-572500D01*
G01X-1172067Y-566083D02*
X-1172567Y-565733D01*
X-1173150Y-565500D01*
X-1173817D01*
X-1174567Y-565850D01*
X-1175150Y-566433D01*
X-1175567Y-567133D01*
X-1175900Y-568300D01*
X-1175983Y-569350D01*
X-1175817Y-570400D01*
X-1175567Y-571100D01*
X-1175067Y-571800D01*
X-1174483Y-572267D01*
X-1173900Y-572500D01*
X-1173317D01*
X-1172733Y-572267D01*
X-1172233Y-571917D01*
X-1171817Y-571450D01*
G01X-1168933Y-565500D02*
Y-570517D01*
X-1168600Y-571567D01*
X-1167933Y-572267D01*
X-1167100Y-572500D01*
X-1166267Y-572267D01*
X-1165600Y-571567D01*
X-1165267Y-570517D01*
Y-565500D01*
G01X-1162467Y-572500D02*
Y-565500D01*
X-1160300Y-571333D01*
X-1158133Y-565500D01*
Y-572500D01*
G01X-1151833D02*
X-1155167D01*
Y-565500D01*
X-1151833D01*
G01X-1153167Y-568883D02*
X-1155167D01*
G01X-1148617Y-572500D02*
Y-565500D01*
X-1144783Y-572500D01*
Y-565500D01*
G01X-1139900D02*
Y-572500D01*
G01X-1141817Y-565500D02*
X-1137983D01*
G01X-1128217Y-572500D02*
Y-565500D01*
X-1124383Y-572500D01*
Y-565500D01*
G01X-1121333D02*
Y-570517D01*
X-1121000Y-571567D01*
X-1120333Y-572267D01*
X-1119500Y-572500D01*
X-1118667Y-572267D01*
X-1118000Y-571567D01*
X-1117667Y-570517D01*
Y-565500D01*
G01X-1114867Y-572500D02*
Y-565500D01*
X-1112700Y-571333D01*
X-1110533Y-565500D01*
Y-572500D01*
G01X-1105233Y-568767D02*
X-1104900Y-568417D01*
X-1104650Y-567833D01*
X-1104483Y-567017D01*
X-1104650Y-566317D01*
X-1104983Y-565850D01*
X-1105567Y-565500D01*
X-1107817D01*
Y-572500D01*
X-1105067D01*
X-1104483Y-572033D01*
X-1104150Y-571333D01*
X-1103983Y-570517D01*
X-1104150Y-569700D01*
X-1104650Y-569000D01*
X-1105233Y-568767D01*
X-1107817D01*
G01X-1097433Y-572500D02*
X-1100767D01*
Y-565500D01*
X-1097433D01*
G01X-1098767Y-568883D02*
X-1100767D01*
G01X-1093967Y-572500D02*
Y-565500D01*
X-1091883D01*
X-1091217Y-565850D01*
X-1090800Y-566317D01*
X-1090633Y-567250D01*
X-1090800Y-568183D01*
X-1091300Y-568767D01*
X-1091883Y-569117D01*
X-1093967D01*
G01X-1091883D02*
X-1090633Y-572500D01*
G01X-1189250Y-531567D02*
X-1188583Y-532150D01*
X-1187833Y-532500D01*
X-1187167D01*
X-1186500Y-532150D01*
X-1186000Y-531567D01*
X-1185750Y-530750D01*
X-1185917Y-529933D01*
X-1186333Y-529233D01*
X-1187083Y-528767D01*
X-1188083Y-528533D01*
X-1188667Y-528067D01*
X-1188917Y-527250D01*
X-1188750Y-526433D01*
X-1188333Y-525850D01*
X-1187750Y-525500D01*
X-1187167D01*
X-1186583Y-525733D01*
X-1186083Y-526317D01*
G01X-1182450Y-532500D02*
Y-525500D01*
G01X-1178950D02*
Y-532500D01*
G01Y-529000D02*
X-1182450D01*
G01X-1172233Y-532500D02*
X-1175567D01*
Y-525500D01*
X-1172233D01*
G01X-1173567Y-528883D02*
X-1175567D01*
G01X-1165433Y-532500D02*
X-1168767D01*
Y-525500D01*
X-1165433D01*
G01X-1166767Y-528883D02*
X-1168767D01*
G01X-1160300Y-525500D02*
Y-532500D01*
G01X-1162217Y-525500D02*
X-1158383D01*
G01X-1146700D02*
Y-532500D01*
G01X-1148617Y-525500D02*
X-1144783D01*
G01X-1140900D02*
X-1138900D01*
G01X-1139900D02*
Y-532500D01*
G01X-1140900D02*
X-1138900D01*
G01X-1133100Y-525500D02*
Y-532500D01*
G01X-1135017Y-525500D02*
X-1131183D01*
G01X-1127967D02*
Y-532500D01*
X-1124633D01*
G01X-1117833D02*
X-1121167D01*
Y-525500D01*
X-1117833D01*
G01X-1119167Y-528883D02*
X-1121167D01*
G01X-1112700Y-532733D02*
X-1112867Y-532617D01*
Y-532383D01*
X-1112700Y-532267D01*
X-1112533Y-532383D01*
Y-532617D01*
X-1112700Y-532733D01*
G01Y-529584D02*
X-1112867Y-529467D01*
Y-529233D01*
X-1112700Y-529117D01*
X-1112533Y-529233D01*
Y-529467D01*
X-1112700Y-529584D01*
G01X-1187500Y-485500D02*
Y-492500D01*
G01X-1189417Y-485500D02*
X-1185583D01*
G01X-1181700D02*
X-1179700D01*
G01X-1180700D02*
Y-492500D01*
G01X-1181700D02*
X-1179700D01*
G01X-1173900Y-485500D02*
Y-492500D01*
G01X-1175817Y-485500D02*
X-1171983D01*
G01X-1168767D02*
Y-492500D01*
X-1165433D01*
G01X-1158633D02*
X-1161967D01*
Y-485500D01*
X-1158633D01*
G01X-1159967Y-488883D02*
X-1161967D01*
G01X-916667Y-570000D02*
Y-563000D01*
X-914583D01*
X-913917Y-563350D01*
X-913500Y-563817D01*
X-913333Y-564750D01*
X-913500Y-565683D01*
X-914000Y-566267D01*
X-914583Y-566617D01*
X-916667D01*
G01X-914583D02*
X-913333Y-570000D01*
G01X-906533D02*
X-909867D01*
Y-563000D01*
X-906533D01*
G01X-907867Y-566383D02*
X-909867D01*
G01X-903483Y-563000D02*
X-901400Y-570000D01*
X-899317Y-563000D01*
G01X-907850Y-451567D02*
X-907183Y-452150D01*
X-906433Y-452500D01*
X-905767D01*
X-905100Y-452150D01*
X-904600Y-451567D01*
X-904350Y-450750D01*
X-904517Y-449933D01*
X-904933Y-449233D01*
X-905683Y-448767D01*
X-906683Y-448533D01*
X-907267Y-448067D01*
X-907517Y-447250D01*
X-907350Y-446433D01*
X-906933Y-445850D01*
X-906350Y-445500D01*
X-905767D01*
X-905183Y-445733D01*
X-904683Y-446317D01*
G01X-897467Y-446083D02*
X-897967Y-445733D01*
X-898550Y-445500D01*
X-899217D01*
X-899967Y-445850D01*
X-900550Y-446433D01*
X-900967Y-447133D01*
X-901300Y-448300D01*
X-901383Y-449350D01*
X-901217Y-450400D01*
X-900967Y-451100D01*
X-900467Y-451800D01*
X-899883Y-452267D01*
X-899300Y-452500D01*
X-898717D01*
X-898133Y-452267D01*
X-897633Y-451917D01*
X-897217Y-451450D01*
G01X-894583Y-452500D02*
X-892500Y-445500D01*
X-890417Y-452500D01*
G01X-891167Y-450050D02*
X-893833D01*
G01X-887367Y-445500D02*
Y-452500D01*
X-884033D01*
G01X-877233D02*
X-880567D01*
Y-445500D01*
X-877233D01*
G01X-878567Y-448883D02*
X-880567D01*
G01X-874333Y-572500D02*
Y-565500D01*
X-872667D01*
X-872000Y-565850D01*
X-871500Y-566317D01*
X-871083Y-567017D01*
X-870750Y-567833D01*
X-870667Y-569000D01*
X-870750Y-570167D01*
X-871083Y-570983D01*
X-871500Y-571684D01*
X-872000Y-572150D01*
X-872667Y-572500D01*
X-874333D01*
G01X-866700Y-565500D02*
X-864700D01*
G01X-865700D02*
Y-572500D01*
G01X-866700D02*
X-864700D01*
G01X-860650Y-571567D02*
X-859983Y-572150D01*
X-859233Y-572500D01*
X-858567D01*
X-857900Y-572150D01*
X-857400Y-571567D01*
X-857150Y-570750D01*
X-857317Y-569933D01*
X-857733Y-569233D01*
X-858483Y-568767D01*
X-859483Y-568533D01*
X-860067Y-568067D01*
X-860317Y-567250D01*
X-860150Y-566433D01*
X-859733Y-565850D01*
X-859150Y-565500D01*
X-858567D01*
X-857983Y-565733D01*
X-857483Y-566317D01*
G01X-850267Y-566083D02*
X-850767Y-565733D01*
X-851350Y-565500D01*
X-852017D01*
X-852767Y-565850D01*
X-853350Y-566433D01*
X-853767Y-567133D01*
X-854100Y-568300D01*
X-854183Y-569350D01*
X-854017Y-570400D01*
X-853767Y-571100D01*
X-853267Y-571800D01*
X-852683Y-572267D01*
X-852100Y-572500D01*
X-851517D01*
X-850933Y-572267D01*
X-850433Y-571917D01*
X-850017Y-571450D01*
G01X-846967Y-565500D02*
Y-572500D01*
X-843633D01*
G01X-838500D02*
X-839167Y-572383D01*
X-839750Y-571917D01*
X-840250Y-571217D01*
X-840583Y-570400D01*
X-840750Y-569467D01*
Y-568533D01*
X-840583Y-567600D01*
X-840250Y-566783D01*
X-839750Y-566083D01*
X-839167Y-565617D01*
X-838500Y-565500D01*
X-837833Y-565617D01*
X-837250Y-566083D01*
X-836750Y-566783D01*
X-836417Y-567600D01*
X-836250Y-568533D01*
Y-569467D01*
X-836417Y-570400D01*
X-836750Y-571217D01*
X-837250Y-571917D01*
X-837833Y-572383D01*
X-838500Y-572500D01*
G01X-833450Y-571567D02*
X-832783Y-572150D01*
X-832033Y-572500D01*
X-831367D01*
X-830700Y-572150D01*
X-830200Y-571567D01*
X-829950Y-570750D01*
X-830117Y-569933D01*
X-830533Y-569233D01*
X-831283Y-568767D01*
X-832283Y-568533D01*
X-832867Y-568067D01*
X-833117Y-567250D01*
X-832950Y-566433D01*
X-832533Y-565850D01*
X-831950Y-565500D01*
X-831367D01*
X-830783Y-565733D01*
X-830283Y-566317D01*
G01X-823233Y-572500D02*
X-826567D01*
Y-565500D01*
X-823233D01*
G01X-824567Y-568883D02*
X-826567D01*
G01X-819933Y-572500D02*
Y-565500D01*
X-818267D01*
X-817600Y-565850D01*
X-817100Y-566317D01*
X-816683Y-567017D01*
X-816350Y-567833D01*
X-816267Y-569000D01*
X-816350Y-570167D01*
X-816683Y-570983D01*
X-817100Y-571684D01*
X-817600Y-572150D01*
X-818267Y-572500D01*
X-819933D01*
G01X-807000Y-565500D02*
X-805833Y-572500D01*
X-804500Y-565500D01*
X-803167Y-572500D01*
X-802000Y-565500D01*
G01X-798700D02*
X-796700D01*
G01X-797700D02*
Y-572500D01*
G01X-798700D02*
X-796700D01*
G01X-790900Y-565500D02*
Y-572500D01*
G01X-792817Y-565500D02*
X-788983D01*
G01X-785850Y-572500D02*
Y-565500D01*
G01X-782350D02*
Y-572500D01*
G01Y-569000D02*
X-785850D01*
G01X-777300Y-572500D02*
X-777967Y-572383D01*
X-778550Y-571917D01*
X-779050Y-571217D01*
X-779383Y-570400D01*
X-779550Y-569467D01*
Y-568533D01*
X-779383Y-567600D01*
X-779050Y-566783D01*
X-778550Y-566083D01*
X-777967Y-565617D01*
X-777300Y-565500D01*
X-776633Y-565617D01*
X-776050Y-566083D01*
X-775550Y-566783D01*
X-775217Y-567600D01*
X-775050Y-568533D01*
Y-569467D01*
X-775217Y-570400D01*
X-775550Y-571217D01*
X-776050Y-571917D01*
X-776633Y-572383D01*
X-777300Y-572500D01*
G01X-772333Y-565500D02*
Y-570517D01*
X-772000Y-571567D01*
X-771333Y-572267D01*
X-770500Y-572500D01*
X-769667Y-572267D01*
X-769000Y-571567D01*
X-768667Y-570517D01*
Y-565500D01*
G01X-763700D02*
Y-572500D01*
G01X-765617Y-565500D02*
X-761783D01*
G01X-750100D02*
Y-572500D01*
G01X-752017Y-565500D02*
X-748183D01*
G01X-745050Y-572500D02*
Y-565500D01*
G01X-741550D02*
Y-572500D01*
G01Y-569000D02*
X-745050D01*
G01X-734833Y-572500D02*
X-738167D01*
Y-565500D01*
X-734833D01*
G01X-736167Y-568883D02*
X-738167D01*
G01X-724567Y-572500D02*
Y-565500D01*
X-722567D01*
X-721900Y-565850D01*
X-721400Y-566667D01*
X-721233Y-567600D01*
X-721400Y-568533D01*
X-721817Y-569233D01*
X-722567Y-569584D01*
X-724567D01*
G01X-717767Y-572500D02*
Y-565500D01*
X-715683D01*
X-715017Y-565850D01*
X-714600Y-566317D01*
X-714433Y-567250D01*
X-714600Y-568183D01*
X-715100Y-568767D01*
X-715683Y-569117D01*
X-717767D01*
G01X-715683D02*
X-714433Y-572500D01*
G01X-710300Y-565500D02*
X-708300D01*
G01X-709300D02*
Y-572500D01*
G01X-710300D02*
X-708300D01*
G01X-702500D02*
X-703167Y-572383D01*
X-703750Y-571917D01*
X-704250Y-571217D01*
X-704583Y-570400D01*
X-704750Y-569467D01*
Y-568533D01*
X-704583Y-567600D01*
X-704250Y-566783D01*
X-703750Y-566083D01*
X-703167Y-565617D01*
X-702500Y-565500D01*
X-701833Y-565617D01*
X-701250Y-566083D01*
X-700750Y-566783D01*
X-700417Y-567600D01*
X-700250Y-568533D01*
Y-569467D01*
X-700417Y-570400D01*
X-700750Y-571217D01*
X-701250Y-571917D01*
X-701833Y-572383D01*
X-702500Y-572500D01*
G01X-697367D02*
Y-565500D01*
X-695283D01*
X-694617Y-565850D01*
X-694200Y-566317D01*
X-694033Y-567250D01*
X-694200Y-568183D01*
X-694700Y-568767D01*
X-695283Y-569117D01*
X-697367D01*
G01X-695283D02*
X-694033Y-572500D01*
G01X-684600Y-565500D02*
X-683433Y-572500D01*
X-682100Y-565500D01*
X-680767Y-572500D01*
X-679600Y-565500D01*
G01X-676967Y-572500D02*
Y-565500D01*
X-674883D01*
X-674217Y-565850D01*
X-673800Y-566317D01*
X-673633Y-567250D01*
X-673800Y-568183D01*
X-674300Y-568767D01*
X-674883Y-569117D01*
X-676967D01*
G01X-674883D02*
X-673633Y-572500D01*
G01X-669500Y-565500D02*
X-667500D01*
G01X-668500D02*
Y-572500D01*
G01X-669500D02*
X-667500D01*
G01X-661700Y-565500D02*
Y-572500D01*
G01X-663617Y-565500D02*
X-659783D01*
G01X-654900D02*
Y-572500D01*
G01X-656817Y-565500D02*
X-652983D01*
G01X-646433Y-572500D02*
X-649767D01*
Y-565500D01*
X-646433D01*
G01X-647767Y-568883D02*
X-649767D01*
G01X-643217Y-572500D02*
Y-565500D01*
X-639383Y-572500D01*
Y-565500D01*
G01X-625867Y-566083D02*
X-626367Y-565733D01*
X-626950Y-565500D01*
X-627617D01*
X-628367Y-565850D01*
X-628950Y-566433D01*
X-629367Y-567133D01*
X-629700Y-568300D01*
X-629783Y-569350D01*
X-629617Y-570400D01*
X-629367Y-571100D01*
X-628867Y-571800D01*
X-628283Y-572267D01*
X-627700Y-572500D01*
X-627117D01*
X-626533Y-572267D01*
X-626033Y-571917D01*
X-625617Y-571450D01*
G01X-620900Y-572500D02*
X-621567Y-572383D01*
X-622150Y-571917D01*
X-622650Y-571217D01*
X-622983Y-570400D01*
X-623150Y-569467D01*
Y-568533D01*
X-622983Y-567600D01*
X-622650Y-566783D01*
X-622150Y-566083D01*
X-621567Y-565617D01*
X-620900Y-565500D01*
X-620233Y-565617D01*
X-619650Y-566083D01*
X-619150Y-566783D01*
X-618817Y-567600D01*
X-618650Y-568533D01*
Y-569467D01*
X-618817Y-570400D01*
X-619150Y-571217D01*
X-619650Y-571917D01*
X-620233Y-572383D01*
X-620900Y-572500D01*
G01X-616017D02*
Y-565500D01*
X-612183Y-572500D01*
Y-565500D01*
G01X-609050Y-571567D02*
X-608383Y-572150D01*
X-607633Y-572500D01*
X-606967D01*
X-606300Y-572150D01*
X-605800Y-571567D01*
X-605550Y-570750D01*
X-605717Y-569933D01*
X-606133Y-569233D01*
X-606883Y-568767D01*
X-607883Y-568533D01*
X-608467Y-568067D01*
X-608717Y-567250D01*
X-608550Y-566433D01*
X-608133Y-565850D01*
X-607550Y-565500D01*
X-606967D01*
X-606383Y-565733D01*
X-605883Y-566317D01*
G01X-598833Y-572500D02*
X-602167D01*
Y-565500D01*
X-598833D01*
G01X-600167Y-568883D02*
X-602167D01*
G01X-595617Y-572500D02*
Y-565500D01*
X-591783Y-572500D01*
Y-565500D01*
G01X-586900D02*
Y-572500D01*
G01X-588817Y-565500D02*
X-584983D01*
G01X-872500Y-587500D02*
X-873167Y-587383D01*
X-873750Y-586917D01*
X-874250Y-586217D01*
X-874583Y-585400D01*
X-874750Y-584467D01*
Y-583533D01*
X-874583Y-582600D01*
X-874250Y-581783D01*
X-873750Y-581083D01*
X-873167Y-580617D01*
X-872500Y-580500D01*
X-871833Y-580617D01*
X-871250Y-581083D01*
X-870750Y-581783D01*
X-870417Y-582600D01*
X-870250Y-583533D01*
Y-584467D01*
X-870417Y-585400D01*
X-870750Y-586217D01*
X-871250Y-586917D01*
X-871833Y-587383D01*
X-872500Y-587500D01*
G01X-867283D02*
Y-580500D01*
X-864117D01*
G01X-865283Y-583883D02*
X-867283D01*
G01X-854267Y-587500D02*
Y-580500D01*
X-852100Y-586333D01*
X-849933Y-580500D01*
Y-587500D01*
G01X-846300Y-580500D02*
X-844300D01*
G01X-845300D02*
Y-587500D01*
G01X-846300D02*
X-844300D01*
G01X-836667Y-581083D02*
X-837167Y-580733D01*
X-837750Y-580500D01*
X-838417D01*
X-839167Y-580850D01*
X-839750Y-581433D01*
X-840167Y-582133D01*
X-840500Y-583300D01*
X-840583Y-584350D01*
X-840417Y-585400D01*
X-840167Y-586100D01*
X-839667Y-586800D01*
X-839083Y-587267D01*
X-838500Y-587500D01*
X-837917D01*
X-837333Y-587267D01*
X-836833Y-586917D01*
X-836417Y-586450D01*
G01X-833367Y-587500D02*
Y-580500D01*
X-831283D01*
X-830617Y-580850D01*
X-830200Y-581317D01*
X-830033Y-582250D01*
X-830200Y-583183D01*
X-830700Y-583767D01*
X-831283Y-584117D01*
X-833367D01*
G01X-831283D02*
X-830033Y-587500D01*
G01X-824900D02*
X-825567Y-587383D01*
X-826150Y-586917D01*
X-826650Y-586217D01*
X-826983Y-585400D01*
X-827150Y-584467D01*
Y-583533D01*
X-826983Y-582600D01*
X-826650Y-581783D01*
X-826150Y-581083D01*
X-825567Y-580617D01*
X-824900Y-580500D01*
X-824233Y-580617D01*
X-823650Y-581083D01*
X-823150Y-581783D01*
X-822817Y-582600D01*
X-822650Y-583533D01*
Y-584467D01*
X-822817Y-585400D01*
X-823150Y-586217D01*
X-823650Y-586917D01*
X-824233Y-587383D01*
X-824900Y-587500D01*
G01X-819850Y-586567D02*
X-819183Y-587150D01*
X-818433Y-587500D01*
X-817767D01*
X-817100Y-587150D01*
X-816600Y-586567D01*
X-816350Y-585750D01*
X-816517Y-584933D01*
X-816933Y-584233D01*
X-817683Y-583767D01*
X-818683Y-583533D01*
X-819267Y-583067D01*
X-819517Y-582250D01*
X-819350Y-581433D01*
X-818933Y-580850D01*
X-818350Y-580500D01*
X-817767D01*
X-817183Y-580733D01*
X-816683Y-581317D01*
G01X-811300Y-587500D02*
X-811967Y-587383D01*
X-812550Y-586917D01*
X-813050Y-586217D01*
X-813383Y-585400D01*
X-813550Y-584467D01*
Y-583533D01*
X-813383Y-582600D01*
X-813050Y-581783D01*
X-812550Y-581083D01*
X-811967Y-580617D01*
X-811300Y-580500D01*
X-810633Y-580617D01*
X-810050Y-581083D01*
X-809550Y-581783D01*
X-809217Y-582600D01*
X-809050Y-583533D01*
Y-584467D01*
X-809217Y-585400D01*
X-809550Y-586217D01*
X-810050Y-586917D01*
X-810633Y-587383D01*
X-811300Y-587500D01*
G01X-806083D02*
Y-580500D01*
X-802917D01*
G01X-804083Y-583883D02*
X-806083D01*
G01X-797700Y-580500D02*
Y-587500D01*
G01X-799617Y-580500D02*
X-795783D01*
G01X-782267Y-581083D02*
X-782767Y-580733D01*
X-783350Y-580500D01*
X-784017D01*
X-784767Y-580850D01*
X-785350Y-581433D01*
X-785767Y-582133D01*
X-786100Y-583300D01*
X-786183Y-584350D01*
X-786017Y-585400D01*
X-785767Y-586100D01*
X-785267Y-586800D01*
X-784683Y-587267D01*
X-784100Y-587500D01*
X-783517D01*
X-782933Y-587267D01*
X-782433Y-586917D01*
X-782017Y-586450D01*
G01X-777300Y-587500D02*
X-777967Y-587383D01*
X-778550Y-586917D01*
X-779050Y-586217D01*
X-779383Y-585400D01*
X-779550Y-584467D01*
Y-583533D01*
X-779383Y-582600D01*
X-779050Y-581783D01*
X-778550Y-581083D01*
X-777967Y-580617D01*
X-777300Y-580500D01*
X-776633Y-580617D01*
X-776050Y-581083D01*
X-775550Y-581783D01*
X-775217Y-582600D01*
X-775050Y-583533D01*
Y-584467D01*
X-775217Y-585400D01*
X-775550Y-586217D01*
X-776050Y-586917D01*
X-776633Y-587383D01*
X-777300Y-587500D01*
G01X-772167D02*
Y-580500D01*
X-770083D01*
X-769417Y-580850D01*
X-769000Y-581317D01*
X-768833Y-582250D01*
X-769000Y-583183D01*
X-769500Y-583767D01*
X-770083Y-584117D01*
X-772167D01*
G01X-770083D02*
X-768833Y-587500D01*
G01X-765367D02*
Y-580500D01*
X-763367D01*
X-762700Y-580850D01*
X-762200Y-581667D01*
X-762033Y-582600D01*
X-762200Y-583533D01*
X-762617Y-584233D01*
X-763367Y-584584D01*
X-765367D01*
G01X-756900Y-587500D02*
X-757567Y-587383D01*
X-758150Y-586917D01*
X-758650Y-586217D01*
X-758983Y-585400D01*
X-759150Y-584467D01*
Y-583533D01*
X-758983Y-582600D01*
X-758650Y-581783D01*
X-758150Y-581083D01*
X-757567Y-580617D01*
X-756900Y-580500D01*
X-756233Y-580617D01*
X-755650Y-581083D01*
X-755150Y-581783D01*
X-754817Y-582600D01*
X-754650Y-583533D01*
Y-584467D01*
X-754817Y-585400D01*
X-755150Y-586217D01*
X-755650Y-586917D01*
X-756233Y-587383D01*
X-756900Y-587500D01*
G01X-751767D02*
Y-580500D01*
X-749683D01*
X-749017Y-580850D01*
X-748600Y-581317D01*
X-748433Y-582250D01*
X-748600Y-583183D01*
X-749100Y-583767D01*
X-749683Y-584117D01*
X-751767D01*
G01X-749683D02*
X-748433Y-587500D01*
G01X-745383D02*
X-743300Y-580500D01*
X-741217Y-587500D01*
G01X-741967Y-585050D02*
X-744633D01*
G01X-736500Y-580500D02*
Y-587500D01*
G01X-738417Y-580500D02*
X-734583D01*
G01X-730700D02*
X-728700D01*
G01X-729700D02*
Y-587500D01*
G01X-730700D02*
X-728700D01*
G01X-722900D02*
X-723567Y-587383D01*
X-724150Y-586917D01*
X-724650Y-586217D01*
X-724983Y-585400D01*
X-725150Y-584467D01*
Y-583533D01*
X-724983Y-582600D01*
X-724650Y-581783D01*
X-724150Y-581083D01*
X-723567Y-580617D01*
X-722900Y-580500D01*
X-722233Y-580617D01*
X-721650Y-581083D01*
X-721150Y-581783D01*
X-720817Y-582600D01*
X-720650Y-583533D01*
Y-584467D01*
X-720817Y-585400D01*
X-721150Y-586217D01*
X-721650Y-586917D01*
X-722233Y-587383D01*
X-722900Y-587500D01*
G01X-718017D02*
Y-580500D01*
X-714183Y-587500D01*
Y-580500D01*
G01X-709300Y-587733D02*
X-709467Y-587617D01*
Y-587383D01*
X-709300Y-587267D01*
X-709133Y-587383D01*
Y-587617D01*
X-709300Y-587733D01*
G01X-870667Y-551083D02*
X-871167Y-550733D01*
X-871750Y-550500D01*
X-872417D01*
X-873167Y-550850D01*
X-873750Y-551433D01*
X-874167Y-552133D01*
X-874500Y-553300D01*
X-874583Y-554350D01*
X-874417Y-555400D01*
X-874167Y-556100D01*
X-873667Y-556800D01*
X-873083Y-557267D01*
X-872500Y-557500D01*
X-871917D01*
X-871333Y-557267D01*
X-870833Y-556917D01*
X-870417Y-556450D01*
G01X-865700Y-557500D02*
X-866367Y-557383D01*
X-866950Y-556917D01*
X-867450Y-556217D01*
X-867783Y-555400D01*
X-867950Y-554467D01*
Y-553533D01*
X-867783Y-552600D01*
X-867450Y-551783D01*
X-866950Y-551083D01*
X-866367Y-550617D01*
X-865700Y-550500D01*
X-865033Y-550617D01*
X-864450Y-551083D01*
X-863950Y-551783D01*
X-863617Y-552600D01*
X-863450Y-553533D01*
Y-554467D01*
X-863617Y-555400D01*
X-863950Y-556217D01*
X-864450Y-556917D01*
X-865033Y-557383D01*
X-865700Y-557500D01*
G01X-860817D02*
Y-550500D01*
X-856983Y-557500D01*
Y-550500D01*
G01X-853683Y-557500D02*
Y-550500D01*
X-850517D01*
G01X-851683Y-553883D02*
X-853683D01*
G01X-846300Y-550500D02*
X-844300D01*
G01X-845300D02*
Y-557500D01*
G01X-846300D02*
X-844300D01*
G01X-840333D02*
Y-550500D01*
X-838667D01*
X-838000Y-550850D01*
X-837500Y-551317D01*
X-837083Y-552017D01*
X-836750Y-552833D01*
X-836667Y-554000D01*
X-836750Y-555167D01*
X-837083Y-555983D01*
X-837500Y-556684D01*
X-838000Y-557150D01*
X-838667Y-557500D01*
X-840333D01*
G01X-830033D02*
X-833367D01*
Y-550500D01*
X-830033D01*
G01X-831367Y-553883D02*
X-833367D01*
G01X-826817Y-557500D02*
Y-550500D01*
X-822983Y-557500D01*
Y-550500D01*
G01X-816267Y-551083D02*
X-816767Y-550733D01*
X-817350Y-550500D01*
X-818017D01*
X-818767Y-550850D01*
X-819350Y-551433D01*
X-819767Y-552133D01*
X-820100Y-553300D01*
X-820183Y-554350D01*
X-820017Y-555400D01*
X-819767Y-556100D01*
X-819267Y-556800D01*
X-818683Y-557267D01*
X-818100Y-557500D01*
X-817517D01*
X-816933Y-557267D01*
X-816433Y-556917D01*
X-816017Y-556450D01*
G01X-809633Y-557500D02*
X-812967D01*
Y-550500D01*
X-809633D01*
G01X-810967Y-553883D02*
X-812967D01*
G01X-799783Y-557500D02*
X-797700Y-550500D01*
X-795617Y-557500D01*
G01X-796367Y-555050D02*
X-799033D01*
G01X-792817Y-557500D02*
Y-550500D01*
X-788983Y-557500D01*
Y-550500D01*
G01X-785933Y-557500D02*
Y-550500D01*
X-784267D01*
X-783600Y-550850D01*
X-783100Y-551317D01*
X-782683Y-552017D01*
X-782350Y-552833D01*
X-782267Y-554000D01*
X-782350Y-555167D01*
X-782683Y-555983D01*
X-783100Y-556684D01*
X-783600Y-557150D01*
X-784267Y-557500D01*
X-785933D01*
G01X-771500Y-550500D02*
X-769500D01*
G01X-770500D02*
Y-557500D01*
G01X-771500D02*
X-769500D01*
G01X-763700Y-550500D02*
Y-557500D01*
G01X-765617Y-550500D02*
X-761783D01*
G01X-758650Y-556567D02*
X-757983Y-557150D01*
X-757233Y-557500D01*
X-756567D01*
X-755900Y-557150D01*
X-755400Y-556567D01*
X-755150Y-555750D01*
X-755317Y-554933D01*
X-755733Y-554233D01*
X-756483Y-553767D01*
X-757483Y-553533D01*
X-758067Y-553067D01*
X-758317Y-552250D01*
X-758150Y-551433D01*
X-757733Y-550850D01*
X-757150Y-550500D01*
X-756567D01*
X-755983Y-550733D01*
X-755483Y-551317D01*
G01X-741467Y-551083D02*
X-741967Y-550733D01*
X-742550Y-550500D01*
X-743217D01*
X-743967Y-550850D01*
X-744550Y-551433D01*
X-744967Y-552133D01*
X-745300Y-553300D01*
X-745383Y-554350D01*
X-745217Y-555400D01*
X-744967Y-556100D01*
X-744467Y-556800D01*
X-743883Y-557267D01*
X-743300Y-557500D01*
X-742717D01*
X-742133Y-557267D01*
X-741633Y-556917D01*
X-741217Y-556450D01*
G01X-736500Y-557500D02*
X-737167Y-557383D01*
X-737750Y-556917D01*
X-738250Y-556217D01*
X-738583Y-555400D01*
X-738750Y-554467D01*
Y-553533D01*
X-738583Y-552600D01*
X-738250Y-551783D01*
X-737750Y-551083D01*
X-737167Y-550617D01*
X-736500Y-550500D01*
X-735833Y-550617D01*
X-735250Y-551083D01*
X-734750Y-551783D01*
X-734417Y-552600D01*
X-734250Y-553533D01*
Y-554467D01*
X-734417Y-555400D01*
X-734750Y-556217D01*
X-735250Y-556917D01*
X-735833Y-557383D01*
X-736500Y-557500D01*
G01X-731617D02*
Y-550500D01*
X-727783Y-557500D01*
Y-550500D01*
G01X-722900D02*
Y-557500D01*
G01X-724817Y-550500D02*
X-720983D01*
G01X-714433Y-557500D02*
X-717767D01*
Y-550500D01*
X-714433D01*
G01X-715767Y-553883D02*
X-717767D01*
G01X-711217Y-557500D02*
Y-550500D01*
X-707383Y-557500D01*
Y-550500D01*
G01X-702500D02*
Y-557500D01*
G01X-704417Y-550500D02*
X-700583D01*
G01X-697450Y-556567D02*
X-696783Y-557150D01*
X-696033Y-557500D01*
X-695367D01*
X-694700Y-557150D01*
X-694200Y-556567D01*
X-693950Y-555750D01*
X-694117Y-554933D01*
X-694533Y-554233D01*
X-695283Y-553767D01*
X-696283Y-553533D01*
X-696867Y-553067D01*
X-697117Y-552250D01*
X-696950Y-551433D01*
X-696533Y-550850D01*
X-695950Y-550500D01*
X-695367D01*
X-694783Y-550733D01*
X-694283Y-551317D01*
G01X-684267Y-557500D02*
Y-550500D01*
X-682100Y-556333D01*
X-679933Y-550500D01*
Y-557500D01*
G01X-677383D02*
X-675300Y-550500D01*
X-673217Y-557500D01*
G01X-673967Y-555050D02*
X-676633D01*
G01X-668500Y-557500D02*
Y-554350D01*
X-670167Y-550500D01*
G01X-666833D02*
X-668500Y-554350D01*
G01X-656817Y-557500D02*
Y-550500D01*
X-652983Y-557500D01*
Y-550500D01*
G01X-648100Y-557500D02*
X-648767Y-557383D01*
X-649350Y-556917D01*
X-649850Y-556217D01*
X-650183Y-555400D01*
X-650350Y-554467D01*
Y-553533D01*
X-650183Y-552600D01*
X-649850Y-551783D01*
X-649350Y-551083D01*
X-648767Y-550617D01*
X-648100Y-550500D01*
X-647433Y-550617D01*
X-646850Y-551083D01*
X-646350Y-551783D01*
X-646017Y-552600D01*
X-645850Y-553533D01*
Y-554467D01*
X-646017Y-555400D01*
X-646350Y-556217D01*
X-646850Y-556917D01*
X-647433Y-557383D01*
X-648100Y-557500D01*
G01X-641300Y-550500D02*
Y-557500D01*
G01X-643217Y-550500D02*
X-639383D01*
G01X-627033Y-553767D02*
X-626700Y-553417D01*
X-626450Y-552833D01*
X-626283Y-552017D01*
X-626450Y-551317D01*
X-626783Y-550850D01*
X-627367Y-550500D01*
X-629617D01*
Y-557500D01*
X-626867D01*
X-626283Y-557033D01*
X-625950Y-556333D01*
X-625783Y-555517D01*
X-625950Y-554700D01*
X-626450Y-554000D01*
X-627033Y-553767D01*
X-629617D01*
G01X-619233Y-557500D02*
X-622567D01*
Y-550500D01*
X-619233D01*
G01X-620567Y-553883D02*
X-622567D01*
G01X-870667Y-536083D02*
X-871167Y-535733D01*
X-871750Y-535500D01*
X-872417D01*
X-873167Y-535850D01*
X-873750Y-536433D01*
X-874167Y-537133D01*
X-874500Y-538300D01*
X-874583Y-539350D01*
X-874417Y-540400D01*
X-874167Y-541100D01*
X-873667Y-541800D01*
X-873083Y-542267D01*
X-872500Y-542500D01*
X-871917D01*
X-871333Y-542267D01*
X-870833Y-541917D01*
X-870417Y-541450D01*
G01X-865700Y-542500D02*
X-866367Y-542383D01*
X-866950Y-541917D01*
X-867450Y-541217D01*
X-867783Y-540400D01*
X-867950Y-539467D01*
Y-538533D01*
X-867783Y-537600D01*
X-867450Y-536783D01*
X-866950Y-536083D01*
X-866367Y-535617D01*
X-865700Y-535500D01*
X-865033Y-535617D01*
X-864450Y-536083D01*
X-863950Y-536783D01*
X-863617Y-537600D01*
X-863450Y-538533D01*
Y-539467D01*
X-863617Y-540400D01*
X-863950Y-541217D01*
X-864450Y-541917D01*
X-865033Y-542383D01*
X-865700Y-542500D01*
G01X-860567D02*
Y-535500D01*
X-858483D01*
X-857817Y-535850D01*
X-857400Y-536317D01*
X-857233Y-537250D01*
X-857400Y-538183D01*
X-857900Y-538767D01*
X-858483Y-539117D01*
X-860567D01*
G01X-858483D02*
X-857233Y-542500D01*
G01X-853767D02*
Y-535500D01*
X-851767D01*
X-851100Y-535850D01*
X-850600Y-536667D01*
X-850433Y-537600D01*
X-850600Y-538533D01*
X-851017Y-539233D01*
X-851767Y-539584D01*
X-853767D01*
G01X-845300Y-542500D02*
X-845967Y-542383D01*
X-846550Y-541917D01*
X-847050Y-541217D01*
X-847383Y-540400D01*
X-847550Y-539467D01*
Y-538533D01*
X-847383Y-537600D01*
X-847050Y-536783D01*
X-846550Y-536083D01*
X-845967Y-535617D01*
X-845300Y-535500D01*
X-844633Y-535617D01*
X-844050Y-536083D01*
X-843550Y-536783D01*
X-843217Y-537600D01*
X-843050Y-538533D01*
Y-539467D01*
X-843217Y-540400D01*
X-843550Y-541217D01*
X-844050Y-541917D01*
X-844633Y-542383D01*
X-845300Y-542500D01*
G01X-840167D02*
Y-535500D01*
X-838083D01*
X-837417Y-535850D01*
X-837000Y-536317D01*
X-836833Y-537250D01*
X-837000Y-538183D01*
X-837500Y-538767D01*
X-838083Y-539117D01*
X-840167D01*
G01X-838083D02*
X-836833Y-542500D01*
G01X-833783D02*
X-831700Y-535500D01*
X-829617Y-542500D01*
G01X-830367Y-540050D02*
X-833033D01*
G01X-824900Y-535500D02*
Y-542500D01*
G01X-826817Y-535500D02*
X-822983D01*
G01X-819100D02*
X-817100D01*
G01X-818100D02*
Y-542500D01*
G01X-819100D02*
X-817100D01*
G01X-811300D02*
X-811967Y-542383D01*
X-812550Y-541917D01*
X-813050Y-541217D01*
X-813383Y-540400D01*
X-813550Y-539467D01*
Y-538533D01*
X-813383Y-537600D01*
X-813050Y-536783D01*
X-812550Y-536083D01*
X-811967Y-535617D01*
X-811300Y-535500D01*
X-810633Y-535617D01*
X-810050Y-536083D01*
X-809550Y-536783D01*
X-809217Y-537600D01*
X-809050Y-538533D01*
Y-539467D01*
X-809217Y-540400D01*
X-809550Y-541217D01*
X-810050Y-541917D01*
X-810633Y-542383D01*
X-811300Y-542500D01*
G01X-806417D02*
Y-535500D01*
X-802583Y-542500D01*
Y-535500D01*
G01X-797700Y-542733D02*
X-797867Y-542617D01*
Y-542383D01*
X-797700Y-542267D01*
X-797533Y-542383D01*
Y-542617D01*
X-797700Y-542733D01*
G01X-784100Y-535500D02*
Y-542500D01*
G01X-786017Y-535500D02*
X-782183D01*
G01X-779050Y-542500D02*
Y-535500D01*
G01X-775550D02*
Y-542500D01*
G01Y-539000D02*
X-779050D01*
G01X-771500Y-535500D02*
X-769500D01*
G01X-770500D02*
Y-542500D01*
G01X-771500D02*
X-769500D01*
G01X-765450Y-541567D02*
X-764783Y-542150D01*
X-764033Y-542500D01*
X-763367D01*
X-762700Y-542150D01*
X-762200Y-541567D01*
X-761950Y-540750D01*
X-762117Y-539933D01*
X-762533Y-539233D01*
X-763283Y-538767D01*
X-764283Y-538533D01*
X-764867Y-538067D01*
X-765117Y-537250D01*
X-764950Y-536433D01*
X-764533Y-535850D01*
X-763950Y-535500D01*
X-763367D01*
X-762783Y-535733D01*
X-762283Y-536317D01*
G01X-751933Y-542500D02*
Y-535500D01*
X-750267D01*
X-749600Y-535850D01*
X-749100Y-536317D01*
X-748683Y-537017D01*
X-748350Y-537833D01*
X-748267Y-539000D01*
X-748350Y-540167D01*
X-748683Y-540983D01*
X-749100Y-541684D01*
X-749600Y-542150D01*
X-750267Y-542500D01*
X-751933D01*
G01X-744967D02*
Y-535500D01*
X-742883D01*
X-742217Y-535850D01*
X-741800Y-536317D01*
X-741633Y-537250D01*
X-741800Y-538183D01*
X-742300Y-538767D01*
X-742883Y-539117D01*
X-744967D01*
G01X-742883D02*
X-741633Y-542500D01*
G01X-738583D02*
X-736500Y-535500D01*
X-734417Y-542500D01*
G01X-735167Y-540050D02*
X-737833D01*
G01X-732200Y-535500D02*
X-731033Y-542500D01*
X-729700Y-535500D01*
X-728367Y-542500D01*
X-727200Y-535500D01*
G01X-723900D02*
X-721900D01*
G01X-722900D02*
Y-542500D01*
G01X-723900D02*
X-721900D01*
G01X-718017D02*
Y-535500D01*
X-714183Y-542500D01*
Y-535500D01*
G01X-708800Y-539000D02*
X-707133D01*
Y-541100D01*
X-707633Y-541800D01*
X-708217Y-542267D01*
X-709050Y-542500D01*
X-709883Y-542267D01*
X-710467Y-541800D01*
X-710967Y-541100D01*
X-711300Y-540283D01*
X-711467Y-539350D01*
Y-538533D01*
X-711300Y-537833D01*
X-710967Y-537017D01*
X-710467Y-536317D01*
X-709967Y-535850D01*
X-709300Y-535500D01*
X-708717D01*
X-708050Y-535733D01*
X-707550Y-536200D01*
G01X-696700Y-535500D02*
X-694700D01*
G01X-695700D02*
Y-542500D01*
G01X-696700D02*
X-694700D01*
G01X-690650Y-541567D02*
X-689983Y-542150D01*
X-689233Y-542500D01*
X-688567D01*
X-687900Y-542150D01*
X-687400Y-541567D01*
X-687150Y-540750D01*
X-687317Y-539933D01*
X-687733Y-539233D01*
X-688483Y-538767D01*
X-689483Y-538533D01*
X-690067Y-538067D01*
X-690317Y-537250D01*
X-690150Y-536433D01*
X-689733Y-535850D01*
X-689150Y-535500D01*
X-688567D01*
X-687983Y-535733D01*
X-687483Y-536317D01*
G01X-676967Y-542500D02*
Y-535500D01*
X-674883D01*
X-674217Y-535850D01*
X-673800Y-536317D01*
X-673633Y-537250D01*
X-673800Y-538183D01*
X-674300Y-538767D01*
X-674883Y-539117D01*
X-676967D01*
G01X-674883D02*
X-673633Y-542500D01*
G01X-666833D02*
X-670167D01*
Y-535500D01*
X-666833D01*
G01X-668167Y-538883D02*
X-670167D01*
G01X-659867Y-536083D02*
X-660367Y-535733D01*
X-660950Y-535500D01*
X-661617D01*
X-662367Y-535850D01*
X-662950Y-536433D01*
X-663367Y-537133D01*
X-663700Y-538300D01*
X-663783Y-539350D01*
X-663617Y-540400D01*
X-663367Y-541100D01*
X-662867Y-541800D01*
X-662283Y-542267D01*
X-661700Y-542500D01*
X-661117D01*
X-660533Y-542267D01*
X-660033Y-541917D01*
X-659617Y-541450D01*
G01X-653233Y-542500D02*
X-656567D01*
Y-535500D01*
X-653233D01*
G01X-654567Y-538883D02*
X-656567D01*
G01X-649100Y-535500D02*
X-647100D01*
G01X-648100D02*
Y-542500D01*
G01X-649100D02*
X-647100D01*
G01X-643383Y-535500D02*
X-641300Y-542500D01*
X-639217Y-535500D01*
G01X-632833Y-542500D02*
X-636167D01*
Y-535500D01*
X-632833D01*
G01X-634167Y-538883D02*
X-636167D01*
G01X-629533Y-542500D02*
Y-535500D01*
X-627867D01*
X-627200Y-535850D01*
X-626700Y-536317D01*
X-626283Y-537017D01*
X-625950Y-537833D01*
X-625867Y-539000D01*
X-625950Y-540167D01*
X-626283Y-540983D01*
X-626700Y-541684D01*
X-627200Y-542150D01*
X-627867Y-542500D01*
X-629533D01*
G01X-615100Y-535500D02*
X-613100D01*
G01X-614100D02*
Y-542500D01*
G01X-615100D02*
X-613100D01*
G01X-609217D02*
Y-535500D01*
X-605383Y-542500D01*
Y-535500D01*
G01X-872500Y-520500D02*
Y-527500D01*
G01X-874417Y-520500D02*
X-870583D01*
G01X-867450Y-527500D02*
Y-520500D01*
G01X-863950D02*
Y-527500D01*
G01Y-524000D02*
X-867450D01*
G01X-857233Y-527500D02*
X-860567D01*
Y-520500D01*
X-857233D01*
G01X-858567Y-523883D02*
X-860567D01*
G01X-846967Y-527500D02*
Y-520500D01*
X-844967D01*
X-844300Y-520850D01*
X-843800Y-521667D01*
X-843633Y-522600D01*
X-843800Y-523533D01*
X-844217Y-524233D01*
X-844967Y-524584D01*
X-846967D01*
G01X-840167Y-527500D02*
Y-520500D01*
X-838083D01*
X-837417Y-520850D01*
X-837000Y-521317D01*
X-836833Y-522250D01*
X-837000Y-523183D01*
X-837500Y-523767D01*
X-838083Y-524117D01*
X-840167D01*
G01X-838083D02*
X-836833Y-527500D01*
G01X-831700D02*
X-832367Y-527383D01*
X-832950Y-526917D01*
X-833450Y-526217D01*
X-833783Y-525400D01*
X-833950Y-524467D01*
Y-523533D01*
X-833783Y-522600D01*
X-833450Y-521783D01*
X-832950Y-521083D01*
X-832367Y-520617D01*
X-831700Y-520500D01*
X-831033Y-520617D01*
X-830450Y-521083D01*
X-829950Y-521783D01*
X-829617Y-522600D01*
X-829450Y-523533D01*
Y-524467D01*
X-829617Y-525400D01*
X-829950Y-526217D01*
X-830450Y-526917D01*
X-831033Y-527383D01*
X-831700Y-527500D01*
G01X-826567D02*
Y-520500D01*
X-824567D01*
X-823900Y-520850D01*
X-823400Y-521667D01*
X-823233Y-522600D01*
X-823400Y-523533D01*
X-823817Y-524233D01*
X-824567Y-524584D01*
X-826567D01*
G01X-819767Y-527500D02*
Y-520500D01*
X-817683D01*
X-817017Y-520850D01*
X-816600Y-521317D01*
X-816433Y-522250D01*
X-816600Y-523183D01*
X-817100Y-523767D01*
X-817683Y-524117D01*
X-819767D01*
G01X-817683D02*
X-816433Y-527500D01*
G01X-812300Y-520500D02*
X-810300D01*
G01X-811300D02*
Y-527500D01*
G01X-812300D02*
X-810300D01*
G01X-802833D02*
X-806167D01*
Y-520500D01*
X-802833D01*
G01X-804167Y-523883D02*
X-806167D01*
G01X-797700Y-520500D02*
Y-527500D01*
G01X-799617Y-520500D02*
X-795783D01*
G01X-792983Y-527500D02*
X-790900Y-520500D01*
X-788817Y-527500D01*
G01X-789567Y-525050D02*
X-792233D01*
G01X-785767Y-527500D02*
Y-520500D01*
X-783683D01*
X-783017Y-520850D01*
X-782600Y-521317D01*
X-782433Y-522250D01*
X-782600Y-523183D01*
X-783100Y-523767D01*
X-783683Y-524117D01*
X-785767D01*
G01X-783683D02*
X-782433Y-527500D01*
G01X-777300D02*
Y-524350D01*
X-778967Y-520500D01*
G01X-775633D02*
X-777300Y-524350D01*
G01X-765367Y-527500D02*
Y-520500D01*
X-763367D01*
X-762700Y-520850D01*
X-762200Y-521667D01*
X-762033Y-522600D01*
X-762200Y-523533D01*
X-762617Y-524233D01*
X-763367Y-524584D01*
X-765367D01*
G01X-758567Y-527500D02*
Y-520500D01*
X-756483D01*
X-755817Y-520850D01*
X-755400Y-521317D01*
X-755233Y-522250D01*
X-755400Y-523183D01*
X-755900Y-523767D01*
X-756483Y-524117D01*
X-758567D01*
G01X-756483D02*
X-755233Y-527500D01*
G01X-750100D02*
X-750767Y-527383D01*
X-751350Y-526917D01*
X-751850Y-526217D01*
X-752183Y-525400D01*
X-752350Y-524467D01*
Y-523533D01*
X-752183Y-522600D01*
X-751850Y-521783D01*
X-751350Y-521083D01*
X-750767Y-520617D01*
X-750100Y-520500D01*
X-749433Y-520617D01*
X-748850Y-521083D01*
X-748350Y-521783D01*
X-748017Y-522600D01*
X-747850Y-523533D01*
Y-524467D01*
X-748017Y-525400D01*
X-748350Y-526217D01*
X-748850Y-526917D01*
X-749433Y-527383D01*
X-750100Y-527500D01*
G01X-744967D02*
Y-520500D01*
X-742967D01*
X-742300Y-520850D01*
X-741800Y-521667D01*
X-741633Y-522600D01*
X-741800Y-523533D01*
X-742217Y-524233D01*
X-742967Y-524584D01*
X-744967D01*
G01X-734833Y-527500D02*
X-738167D01*
Y-520500D01*
X-734833D01*
G01X-736167Y-523883D02*
X-738167D01*
G01X-731367Y-527500D02*
Y-520500D01*
X-729283D01*
X-728617Y-520850D01*
X-728200Y-521317D01*
X-728033Y-522250D01*
X-728200Y-523183D01*
X-728700Y-523767D01*
X-729283Y-524117D01*
X-731367D01*
G01X-729283D02*
X-728033Y-527500D01*
G01X-722900Y-520500D02*
Y-527500D01*
G01X-724817Y-520500D02*
X-720983D01*
G01X-716100Y-527500D02*
Y-524350D01*
X-717767Y-520500D01*
G01X-714433D02*
X-716100Y-524350D01*
G01X-702500Y-527500D02*
X-703167Y-527383D01*
X-703750Y-526917D01*
X-704250Y-526217D01*
X-704583Y-525400D01*
X-704750Y-524467D01*
Y-523533D01*
X-704583Y-522600D01*
X-704250Y-521783D01*
X-703750Y-521083D01*
X-703167Y-520617D01*
X-702500Y-520500D01*
X-701833Y-520617D01*
X-701250Y-521083D01*
X-700750Y-521783D01*
X-700417Y-522600D01*
X-700250Y-523533D01*
Y-524467D01*
X-700417Y-525400D01*
X-700750Y-526217D01*
X-701250Y-526917D01*
X-701833Y-527383D01*
X-702500Y-527500D01*
G01X-697283D02*
Y-520500D01*
X-694117D01*
G01X-695283Y-523883D02*
X-697283D01*
G01X-684267Y-527500D02*
Y-520500D01*
X-682100Y-526333D01*
X-679933Y-520500D01*
Y-527500D01*
G01X-676300Y-520500D02*
X-674300D01*
G01X-675300D02*
Y-527500D01*
G01X-676300D02*
X-674300D01*
G01X-666667Y-521083D02*
X-667167Y-520733D01*
X-667750Y-520500D01*
X-668417D01*
X-669167Y-520850D01*
X-669750Y-521433D01*
X-670167Y-522133D01*
X-670500Y-523300D01*
X-670583Y-524350D01*
X-670417Y-525400D01*
X-670167Y-526100D01*
X-669667Y-526800D01*
X-669083Y-527267D01*
X-668500Y-527500D01*
X-667917D01*
X-667333Y-527267D01*
X-666833Y-526917D01*
X-666417Y-526450D01*
G01X-663367Y-527500D02*
Y-520500D01*
X-661283D01*
X-660617Y-520850D01*
X-660200Y-521317D01*
X-660033Y-522250D01*
X-660200Y-523183D01*
X-660700Y-523767D01*
X-661283Y-524117D01*
X-663367D01*
G01X-661283D02*
X-660033Y-527500D01*
G01X-654900D02*
X-655567Y-527383D01*
X-656150Y-526917D01*
X-656650Y-526217D01*
X-656983Y-525400D01*
X-657150Y-524467D01*
Y-523533D01*
X-656983Y-522600D01*
X-656650Y-521783D01*
X-656150Y-521083D01*
X-655567Y-520617D01*
X-654900Y-520500D01*
X-654233Y-520617D01*
X-653650Y-521083D01*
X-653150Y-521783D01*
X-652817Y-522600D01*
X-652650Y-523533D01*
Y-524467D01*
X-652817Y-525400D01*
X-653150Y-526217D01*
X-653650Y-526917D01*
X-654233Y-527383D01*
X-654900Y-527500D01*
G01X-649850Y-526567D02*
X-649183Y-527150D01*
X-648433Y-527500D01*
X-647767D01*
X-647100Y-527150D01*
X-646600Y-526567D01*
X-646350Y-525750D01*
X-646517Y-524933D01*
X-646933Y-524233D01*
X-647683Y-523767D01*
X-648683Y-523533D01*
X-649267Y-523067D01*
X-649517Y-522250D01*
X-649350Y-521433D01*
X-648933Y-520850D01*
X-648350Y-520500D01*
X-647767D01*
X-647183Y-520733D01*
X-646683Y-521317D01*
G01X-641300Y-527500D02*
X-641967Y-527383D01*
X-642550Y-526917D01*
X-643050Y-526217D01*
X-643383Y-525400D01*
X-643550Y-524467D01*
Y-523533D01*
X-643383Y-522600D01*
X-643050Y-521783D01*
X-642550Y-521083D01*
X-641967Y-520617D01*
X-641300Y-520500D01*
X-640633Y-520617D01*
X-640050Y-521083D01*
X-639550Y-521783D01*
X-639217Y-522600D01*
X-639050Y-523533D01*
Y-524467D01*
X-639217Y-525400D01*
X-639550Y-526217D01*
X-640050Y-526917D01*
X-640633Y-527383D01*
X-641300Y-527500D01*
G01X-636083D02*
Y-520500D01*
X-632917D01*
G01X-634083Y-523883D02*
X-636083D01*
G01X-627700Y-520500D02*
Y-527500D01*
G01X-629617Y-520500D02*
X-625783D01*
G01X-872500Y-505500D02*
Y-512500D01*
G01X-874417Y-505500D02*
X-870583D01*
G01X-867450Y-512500D02*
Y-505500D01*
G01X-863950D02*
Y-512500D01*
G01Y-509000D02*
X-867450D01*
G01X-859900Y-505500D02*
X-857900D01*
G01X-858900D02*
Y-512500D01*
G01X-859900D02*
X-857900D01*
G01X-853850Y-511567D02*
X-853183Y-512150D01*
X-852433Y-512500D01*
X-851767D01*
X-851100Y-512150D01*
X-850600Y-511567D01*
X-850350Y-510750D01*
X-850517Y-509933D01*
X-850933Y-509233D01*
X-851683Y-508767D01*
X-852683Y-508533D01*
X-853267Y-508067D01*
X-853517Y-507250D01*
X-853350Y-506433D01*
X-852933Y-505850D01*
X-852350Y-505500D01*
X-851767D01*
X-851183Y-505733D01*
X-850683Y-506317D01*
G01X-840333Y-512500D02*
Y-505500D01*
X-838667D01*
X-838000Y-505850D01*
X-837500Y-506317D01*
X-837083Y-507017D01*
X-836750Y-507833D01*
X-836667Y-509000D01*
X-836750Y-510167D01*
X-837083Y-510983D01*
X-837500Y-511684D01*
X-838000Y-512150D01*
X-838667Y-512500D01*
X-840333D01*
G01X-833367D02*
Y-505500D01*
X-831283D01*
X-830617Y-505850D01*
X-830200Y-506317D01*
X-830033Y-507250D01*
X-830200Y-508183D01*
X-830700Y-508767D01*
X-831283Y-509117D01*
X-833367D01*
G01X-831283D02*
X-830033Y-512500D01*
G01X-826983D02*
X-824900Y-505500D01*
X-822817Y-512500D01*
G01X-823567Y-510050D02*
X-826233D01*
G01X-820600Y-505500D02*
X-819433Y-512500D01*
X-818100Y-505500D01*
X-816767Y-512500D01*
X-815600Y-505500D01*
G01X-812300D02*
X-810300D01*
G01X-811300D02*
Y-512500D01*
G01X-812300D02*
X-810300D01*
G01X-806417D02*
Y-505500D01*
X-802583Y-512500D01*
Y-505500D01*
G01X-797200Y-509000D02*
X-795533D01*
Y-511100D01*
X-796033Y-511800D01*
X-796617Y-512267D01*
X-797450Y-512500D01*
X-798283Y-512267D01*
X-798867Y-511800D01*
X-799367Y-511100D01*
X-799700Y-510283D01*
X-799867Y-509350D01*
Y-508533D01*
X-799700Y-507833D01*
X-799367Y-507017D01*
X-798867Y-506317D01*
X-798367Y-505850D01*
X-797700Y-505500D01*
X-797117D01*
X-796450Y-505733D01*
X-795950Y-506200D01*
G01X-782267Y-506083D02*
X-782767Y-505733D01*
X-783350Y-505500D01*
X-784017D01*
X-784767Y-505850D01*
X-785350Y-506433D01*
X-785767Y-507133D01*
X-786100Y-508300D01*
X-786183Y-509350D01*
X-786017Y-510400D01*
X-785767Y-511100D01*
X-785267Y-511800D01*
X-784683Y-512267D01*
X-784100Y-512500D01*
X-783517D01*
X-782933Y-512267D01*
X-782433Y-511917D01*
X-782017Y-511450D01*
G01X-777300Y-512500D02*
X-777967Y-512383D01*
X-778550Y-511917D01*
X-779050Y-511217D01*
X-779383Y-510400D01*
X-779550Y-509467D01*
Y-508533D01*
X-779383Y-507600D01*
X-779050Y-506783D01*
X-778550Y-506083D01*
X-777967Y-505617D01*
X-777300Y-505500D01*
X-776633Y-505617D01*
X-776050Y-506083D01*
X-775550Y-506783D01*
X-775217Y-507600D01*
X-775050Y-508533D01*
Y-509467D01*
X-775217Y-510400D01*
X-775550Y-511217D01*
X-776050Y-511917D01*
X-776633Y-512383D01*
X-777300Y-512500D01*
G01X-772417D02*
Y-505500D01*
X-768583Y-512500D01*
Y-505500D01*
G01X-763700D02*
Y-512500D01*
G01X-765617Y-505500D02*
X-761783D01*
G01X-758983Y-512500D02*
X-756900Y-505500D01*
X-754817Y-512500D01*
G01X-755567Y-510050D02*
X-758233D01*
G01X-751100Y-505500D02*
X-749100D01*
G01X-750100D02*
Y-512500D01*
G01X-751100D02*
X-749100D01*
G01X-745217D02*
Y-505500D01*
X-741383Y-512500D01*
Y-505500D01*
G01X-738250Y-511567D02*
X-737583Y-512150D01*
X-736833Y-512500D01*
X-736167D01*
X-735500Y-512150D01*
X-735000Y-511567D01*
X-734750Y-510750D01*
X-734917Y-509933D01*
X-735333Y-509233D01*
X-736083Y-508767D01*
X-737083Y-508533D01*
X-737667Y-508067D01*
X-737917Y-507250D01*
X-737750Y-506433D01*
X-737333Y-505850D01*
X-736750Y-505500D01*
X-736167D01*
X-735583Y-505733D01*
X-735083Y-506317D01*
G01X-723900Y-505500D02*
X-721900D01*
G01X-722900D02*
Y-512500D01*
G01X-723900D02*
X-721900D01*
G01X-718017D02*
Y-505500D01*
X-714183Y-512500D01*
Y-505500D01*
G01X-710883Y-512500D02*
Y-505500D01*
X-707717D01*
G01X-708883Y-508883D02*
X-710883D01*
G01X-702500Y-512500D02*
X-703167Y-512383D01*
X-703750Y-511917D01*
X-704250Y-511217D01*
X-704583Y-510400D01*
X-704750Y-509467D01*
Y-508533D01*
X-704583Y-507600D01*
X-704250Y-506783D01*
X-703750Y-506083D01*
X-703167Y-505617D01*
X-702500Y-505500D01*
X-701833Y-505617D01*
X-701250Y-506083D01*
X-700750Y-506783D01*
X-700417Y-507600D01*
X-700250Y-508533D01*
Y-509467D01*
X-700417Y-510400D01*
X-700750Y-511217D01*
X-701250Y-511917D01*
X-701833Y-512383D01*
X-702500Y-512500D01*
G01X-697367D02*
Y-505500D01*
X-695283D01*
X-694617Y-505850D01*
X-694200Y-506317D01*
X-694033Y-507250D01*
X-694200Y-508183D01*
X-694700Y-508767D01*
X-695283Y-509117D01*
X-697367D01*
G01X-695283D02*
X-694033Y-512500D01*
G01X-691067D02*
Y-505500D01*
X-688900Y-511333D01*
X-686733Y-505500D01*
Y-512500D01*
G01X-684183D02*
X-682100Y-505500D01*
X-680017Y-512500D01*
G01X-680767Y-510050D02*
X-683433D01*
G01X-675300Y-505500D02*
Y-512500D01*
G01X-677217Y-505500D02*
X-673383D01*
G01X-669500D02*
X-667500D01*
G01X-668500D02*
Y-512500D01*
G01X-669500D02*
X-667500D01*
G01X-661700D02*
X-662367Y-512383D01*
X-662950Y-511917D01*
X-663450Y-511217D01*
X-663783Y-510400D01*
X-663950Y-509467D01*
Y-508533D01*
X-663783Y-507600D01*
X-663450Y-506783D01*
X-662950Y-506083D01*
X-662367Y-505617D01*
X-661700Y-505500D01*
X-661033Y-505617D01*
X-660450Y-506083D01*
X-659950Y-506783D01*
X-659617Y-507600D01*
X-659450Y-508533D01*
Y-509467D01*
X-659617Y-510400D01*
X-659950Y-511217D01*
X-660450Y-511917D01*
X-661033Y-512383D01*
X-661700Y-512500D01*
G01X-656817D02*
Y-505500D01*
X-652983Y-512500D01*
Y-505500D01*
G01X-643800D02*
X-642633Y-512500D01*
X-641300Y-505500D01*
X-639967Y-512500D01*
X-638800Y-505500D01*
G01X-636250Y-512500D02*
Y-505500D01*
G01X-632750D02*
Y-512500D01*
G01Y-509000D02*
X-636250D01*
G01X-628700Y-505500D02*
X-626700D01*
G01X-627700D02*
Y-512500D01*
G01X-628700D02*
X-626700D01*
G01X-619067Y-506083D02*
X-619567Y-505733D01*
X-620150Y-505500D01*
X-620817D01*
X-621567Y-505850D01*
X-622150Y-506433D01*
X-622567Y-507133D01*
X-622900Y-508300D01*
X-622983Y-509350D01*
X-622817Y-510400D01*
X-622567Y-511100D01*
X-622067Y-511800D01*
X-621483Y-512267D01*
X-620900Y-512500D01*
X-620317D01*
X-619733Y-512267D01*
X-619233Y-511917D01*
X-618817Y-511450D01*
G01X-615850Y-512500D02*
Y-505500D01*
G01X-612350D02*
Y-512500D01*
G01Y-509000D02*
X-615850D01*
G01X-601500Y-505500D02*
X-599500D01*
G01X-600500D02*
Y-512500D01*
G01X-601500D02*
X-599500D01*
G01X-595450Y-511567D02*
X-594783Y-512150D01*
X-594033Y-512500D01*
X-593367D01*
X-592700Y-512150D01*
X-592200Y-511567D01*
X-591950Y-510750D01*
X-592117Y-509933D01*
X-592533Y-509233D01*
X-593283Y-508767D01*
X-594283Y-508533D01*
X-594867Y-508067D01*
X-595117Y-507250D01*
X-594950Y-506433D01*
X-594533Y-505850D01*
X-593950Y-505500D01*
X-593367D01*
X-592783Y-505733D01*
X-592283Y-506317D01*
G01X-858133Y-452500D02*
Y-445500D01*
X-856467D01*
X-855800Y-445850D01*
X-855300Y-446317D01*
X-854883Y-447017D01*
X-854550Y-447833D01*
X-854467Y-449000D01*
X-854550Y-450167D01*
X-854883Y-450983D01*
X-855300Y-451684D01*
X-855800Y-452150D01*
X-856467Y-452500D01*
X-858133D01*
G01X-847833D02*
X-851167D01*
Y-445500D01*
X-847833D01*
G01X-849167Y-448883D02*
X-851167D01*
G01X-844450Y-451567D02*
X-843783Y-452150D01*
X-843033Y-452500D01*
X-842367D01*
X-841700Y-452150D01*
X-841200Y-451567D01*
X-840950Y-450750D01*
X-841117Y-449933D01*
X-841533Y-449233D01*
X-842283Y-448767D01*
X-843283Y-448533D01*
X-843867Y-448067D01*
X-844117Y-447250D01*
X-843950Y-446433D01*
X-843533Y-445850D01*
X-842950Y-445500D01*
X-842367D01*
X-841783Y-445733D01*
X-841283Y-446317D01*
G01X-836900Y-445500D02*
X-834900D01*
G01X-835900D02*
Y-452500D01*
G01X-836900D02*
X-834900D01*
G01X-828600Y-449000D02*
X-826933D01*
Y-451100D01*
X-827433Y-451800D01*
X-828017Y-452267D01*
X-828850Y-452500D01*
X-829683Y-452267D01*
X-830267Y-451800D01*
X-830767Y-451100D01*
X-831100Y-450283D01*
X-831267Y-449350D01*
Y-448533D01*
X-831100Y-447833D01*
X-830767Y-447017D01*
X-830267Y-446317D01*
X-829767Y-445850D01*
X-829100Y-445500D01*
X-828517D01*
X-827850Y-445733D01*
X-827350Y-446200D01*
G01X-824217Y-452500D02*
Y-445500D01*
X-820383Y-452500D01*
Y-445500D01*
G01X-813833Y-452500D02*
X-817167D01*
Y-445500D01*
X-813833D01*
G01X-815167Y-448883D02*
X-817167D01*
G01X-810367Y-452500D02*
Y-445500D01*
X-808283D01*
X-807617Y-445850D01*
X-807200Y-446317D01*
X-807033Y-447250D01*
X-807200Y-448183D01*
X-807700Y-448767D01*
X-808283Y-449117D01*
X-810367D01*
G01X-808283D02*
X-807033Y-452500D01*
G01X-858133D02*
Y-445500D01*
X-856467D01*
X-855800Y-445850D01*
X-855300Y-446317D01*
X-854883Y-447017D01*
X-854550Y-447833D01*
X-854467Y-449000D01*
X-854550Y-450167D01*
X-854883Y-450983D01*
X-855300Y-451684D01*
X-855800Y-452150D01*
X-856467Y-452500D01*
X-858133D01*
G01X-847833D02*
X-851167D01*
Y-445500D01*
X-847833D01*
G01X-849167Y-448883D02*
X-851167D01*
G01X-844450Y-451567D02*
X-843783Y-452150D01*
X-843033Y-452500D01*
X-842367D01*
X-841700Y-452150D01*
X-841200Y-451567D01*
X-840950Y-450750D01*
X-841117Y-449933D01*
X-841533Y-449233D01*
X-842283Y-448767D01*
X-843283Y-448533D01*
X-843867Y-448067D01*
X-844117Y-447250D01*
X-843950Y-446433D01*
X-843533Y-445850D01*
X-842950Y-445500D01*
X-842367D01*
X-841783Y-445733D01*
X-841283Y-446317D01*
G01X-836900Y-445500D02*
X-834900D01*
G01X-835900D02*
Y-452500D01*
G01X-836900D02*
X-834900D01*
G01X-828600Y-449000D02*
X-826933D01*
Y-451100D01*
X-827433Y-451800D01*
X-828017Y-452267D01*
X-828850Y-452500D01*
X-829683Y-452267D01*
X-830267Y-451800D01*
X-830767Y-451100D01*
X-831100Y-450283D01*
X-831267Y-449350D01*
Y-448533D01*
X-831100Y-447833D01*
X-830767Y-447017D01*
X-830267Y-446317D01*
X-829767Y-445850D01*
X-829100Y-445500D01*
X-828517D01*
X-827850Y-445733D01*
X-827350Y-446200D01*
G01X-824217Y-452500D02*
Y-445500D01*
X-820383Y-452500D01*
Y-445500D01*
G01X-813833Y-452500D02*
X-817167D01*
Y-445500D01*
X-813833D01*
G01X-815167Y-448883D02*
X-817167D01*
G01X-810367Y-452500D02*
Y-445500D01*
X-808283D01*
X-807617Y-445850D01*
X-807200Y-446317D01*
X-807033Y-447250D01*
X-807200Y-448183D01*
X-807700Y-448767D01*
X-808283Y-449117D01*
X-810367D01*
G01X-808283D02*
X-807033Y-452500D01*
G01X-642033Y-455000D02*
Y-448000D01*
X-640367D01*
X-639700Y-448350D01*
X-639200Y-448817D01*
X-638783Y-449517D01*
X-638450Y-450333D01*
X-638367Y-451500D01*
X-638450Y-452667D01*
X-638783Y-453483D01*
X-639200Y-454184D01*
X-639700Y-454650D01*
X-640367Y-455000D01*
X-642033D01*
G01X-635483D02*
X-633400Y-448000D01*
X-631317Y-455000D01*
G01X-632067Y-452550D02*
X-634733D01*
G01X-626600Y-448000D02*
Y-455000D01*
G01X-628517Y-448000D02*
X-624683D01*
G01X-618133Y-455000D02*
X-621467D01*
Y-448000D01*
X-618133D01*
G01X-619467Y-451383D02*
X-621467D01*
M02*
